FILE_TYPE = MACRO_DRAWING;
SET COLOR_WIRE YELLOW;
SET COLOR_PROP MONO;
SET COLOR_DOT WHITE;
SET COLOR_ARC YELLOW;
SET COLOR_BODY GREEN;
SET COLOR_NOTE MONO;
SET PROP_DISPLAY VALUE;
SET PAGE_NUMBER P21;
FORCEADD OFFPAGE..5
(-6350 3850);
FORCEPROP 2 LAST $XR5 54 
J 0
(-7024 3850);
DISPLAY 0.638298 (-7024 3850);
PAINT MONO (-7024 3850);
FORCEPROP 2 LAST $XR4 53 
J 0
(-6934 3850);
DISPLAY 0.638298 (-6934 3850);
PAINT MONO (-6934 3850);
FORCEPROP 2 LAST $XR3 52 
J 0
(-6844 3850);
DISPLAY 0.638298 (-6844 3850);
PAINT MONO (-6844 3850);
FORCEPROP 2 LAST $XR2 51 
J 0
(-6754 3850);
DISPLAY 0.638298 (-6754 3850);
PAINT MONO (-6754 3850);
FORCEPROP 2 LAST $XR1 50 
J 0
(-6664 3850);
DISPLAY 0.638298 (-6664 3850);
PAINT MONO (-6664 3850);
FORCEPROP 2 LAST $XR0 49 
J 0
(-6574 3850);
DISPLAY 0.638298 (-6574 3850);
PAINT MONO (-6574 3850);
FORCEPROP 2 LAST PATH I10
J 0
(-6300 3925);
DISPLAY 1.361702 (-6300 3925);
PAINT ORANGE (-6300 3925);
DISPLAY INVISIBLE (-6300 3925);
FORCEPROP 2 LAST CDS_LIB mstr_standard
J 0
(-6350 3850);
PAINT MONO (-6350 3850);
DISPLAY INVISIBLE (-6350 3850);
FORCEPROP 1 LAST OFFPAGE TRUE
J 0
(-6025 3725);
DISPLAY 1.170213 (-6025 3725);
PAINT GREEN (-6025 3725);
DISPLAY INVISIBLE (-6025 3725);
FORCEPROP 1 LAST COMMENT_BODY TRUE
J 0
(-6250 3775);
DISPLAY 1.170213 (-6250 3775);
PAINT PEACH (-6250 3775);
DISPLAY INVISIBLE (-6250 3775);
FORCEADD OFFPAGE..2
(-1800 1150);
FORCEPROP 2 LAST $XR0 112 
J 0
(-1611 1150);
DISPLAY 0.638298 (-1611 1150);
PAINT MONO (-1611 1150);
FORCEPROP 2 LAST PATH I106
J 0
(-1625 1225);
DISPLAY 1.361702 (-1625 1225);
PAINT ORANGE (-1625 1225);
DISPLAY INVISIBLE (-1625 1225);
FORCEPROP 2 LAST CDS_LIB mstr_standard
J 0
(-1800 1150);
PAINT MONO (-1800 1150);
DISPLAY INVISIBLE (-1800 1150);
FORCEPROP 1 LAST OFFPAGE TRUE
J 0
(-1475 1025);
DISPLAY 1.170213 (-1475 1025);
PAINT GREEN (-1475 1025);
DISPLAY INVISIBLE (-1475 1025);
FORCEPROP 1 LAST COMMENT_BODY TRUE
J 0
(-1845 1055);
DISPLAY 1.170213 (-1845 1055);
PAINT PEACH (-1845 1055);
DISPLAY INVISIBLE (-1845 1055);
FORCEADD OFFPAGE..4
(-1400 4500);
FORCEPROP 2 LAST $XR1 113 
J 0
(-1124 4500);
DISPLAY 0.638298 (-1124 4500);
PAINT MONO (-1124 4500);
FORCEPROP 2 LAST $XR0 96 
J 0
(-1214 4500);
DISPLAY 0.638298 (-1214 4500);
PAINT MONO (-1214 4500);
FORCEPROP 2 LAST PATH I107
J 0
(-1225 4575);
DISPLAY 1.361702 (-1225 4575);
PAINT ORANGE (-1225 4575);
DISPLAY INVISIBLE (-1225 4575);
FORCEPROP 2 LAST CDS_LIB mstr_standard
J 0
(-1400 4500);
PAINT MONO (-1400 4500);
DISPLAY INVISIBLE (-1400 4500);
FORCEPROP 1 LAST OFFPAGE TRUE
J 0
(-1075 4375);
DISPLAY 1.170213 (-1075 4375);
PAINT GREEN (-1075 4375);
DISPLAY INVISIBLE (-1075 4375);
FORCEPROP 1 LAST COMMENT_BODY TRUE
J 0
(-1425 4400);
DISPLAY 1.170213 (-1425 4400);
PAINT PEACH (-1425 4400);
DISPLAY INVISIBLE (-1425 4400);
FORCEADD OFFPAGE..1
R 2
(-1400 4450);
FORCEPROP 2 LAST $XR0 96 
J 0
(-1214 4450);
DISPLAY 0.638298 (-1214 4450);
PAINT MONO (-1214 4450);
FORCEPROP 2 LAST CDS_LIB mstr_standard
J 2
(-1400 4450);
PAINT MONO (-1400 4450);
DISPLAY INVISIBLE (-1400 4450);
FORCEPROP 2 LAST PATH I108
J 2
(-1575 4525);
DISPLAY 1.361702 (-1575 4525);
PAINT ORANGE (-1575 4525);
DISPLAY INVISIBLE (-1575 4525);
FORCEPROP 1 LAST OFFPAGE TRUE
J 2
(-1725 4325);
DISPLAY 0.872340 (-1725 4325);
PAINT GREEN (-1725 4325);
DISPLAY INVISIBLE (-1725 4325);
FORCEPROP 1 LAST COMMENT_BODY TRUE
J 2
(-1525 4350);
DISPLAY 0.872340 (-1525 4350);
PAINT GREEN (-1525 4350);
DISPLAY INVISIBLE (-1525 4350);
FORCEADD OFFPAGE..1
(-6325 3750);
FORCEPROP 2 LAST $XR2 152 
J 0
(-6786 3750);
DISPLAY 0.638298 (-6786 3750);
PAINT MONO (-6786 3750);
FORCEPROP 2 LAST $XR1 95 
J 0
(-6666 3750);
DISPLAY 0.638298 (-6666 3750);
PAINT MONO (-6666 3750);
FORCEPROP 2 LAST $XR0 94 
J 0
(-6576 3750);
DISPLAY 0.638298 (-6576 3750);
PAINT MONO (-6576 3750);
FORCEPROP 2 LAST PATH I11
J 0
(-6275 3825);
DISPLAY 1.361702 (-6275 3825);
PAINT ORANGE (-6275 3825);
DISPLAY INVISIBLE (-6275 3825);
FORCEPROP 2 LAST CDS_LIB mstr_standard
J 0
(-6325 3750);
PAINT MONO (-6325 3750);
DISPLAY INVISIBLE (-6325 3750);
FORCEPROP 1 LAST OFFPAGE TRUE
J 0
(-6000 3625);
DISPLAY 0.872340 (-6000 3625);
PAINT GREEN (-6000 3625);
DISPLAY INVISIBLE (-6000 3625);
FORCEPROP 1 LAST COMMENT_BODY TRUE
J 0
(-6200 3650);
DISPLAY 0.872340 (-6200 3650);
PAINT GREEN (-6200 3650);
DISPLAY INVISIBLE (-6200 3650);
FORCEADD OFFPAGE..3
(-1825 3350);
FORCEPROP 2 LAST $XR0 92 
J 0
(-1611 3350);
DISPLAY 0.638298 (-1611 3350);
PAINT MONO (-1611 3350);
FORCEPROP 2 LAST PATH I111
J 0
(-1650 3425);
DISPLAY 1.361702 (-1650 3425);
PAINT ORANGE (-1650 3425);
DISPLAY INVISIBLE (-1650 3425);
FORCEPROP 2 LAST CDS_LIB mstr_standard
J 0
(-1825 3350);
PAINT MONO (-1825 3350);
DISPLAY INVISIBLE (-1825 3350);
FORCEPROP 1 LAST OFFPAGE TRUE
J 0
(-1500 3225);
DISPLAY 1.170213 (-1500 3225);
PAINT GREEN (-1500 3225);
DISPLAY INVISIBLE (-1500 3225);
FORCEPROP 1 LAST COMMENT_BODY TRUE
J 0
(-1875 3250);
DISPLAY 1.170213 (-1875 3250);
PAINT PEACH (-1875 3250);
DISPLAY INVISIBLE (-1875 3250);
FORCEADD OFFPAGE..1
(-6325 3700);
FORCEPROP 2 LAST $XR2 152 
J 0
(-6786 3700);
DISPLAY 0.638298 (-6786 3700);
PAINT MONO (-6786 3700);
FORCEPROP 2 LAST $XR1 95 
J 0
(-6666 3700);
DISPLAY 0.638298 (-6666 3700);
PAINT MONO (-6666 3700);
FORCEPROP 2 LAST $XR0 94 
J 0
(-6576 3700);
DISPLAY 0.638298 (-6576 3700);
PAINT MONO (-6576 3700);
FORCEPROP 2 LAST PATH I12
J 0
(-6275 3775);
DISPLAY 1.361702 (-6275 3775);
PAINT ORANGE (-6275 3775);
DISPLAY INVISIBLE (-6275 3775);
FORCEPROP 2 LAST CDS_LIB mstr_standard
J 0
(-6325 3700);
PAINT MONO (-6325 3700);
DISPLAY INVISIBLE (-6325 3700);
FORCEPROP 1 LAST OFFPAGE TRUE
J 0
(-6000 3575);
DISPLAY 0.872340 (-6000 3575);
PAINT GREEN (-6000 3575);
DISPLAY INVISIBLE (-6000 3575);
FORCEPROP 1 LAST COMMENT_BODY TRUE
J 0
(-6200 3600);
DISPLAY 0.872340 (-6200 3600);
PAINT GREEN (-6200 3600);
DISPLAY INVISIBLE (-6200 3600);
FORCEADD OFFPAGE..5
(-6025 2900);
FORCEPROP 2 LAST $XR0 99 
J 0
(-6279 2900);
DISPLAY 0.638298 (-6279 2900);
PAINT MONO (-6279 2900);
FORCEPROP 2 LAST CDS_LIB mstr_standard
J 0
(-6025 2900);
PAINT MONO (-6025 2900);
DISPLAY INVISIBLE (-6025 2900);
FORCEPROP 2 LAST PATH I133
J 0
(-6225 2950);
DISPLAY 1.361702 (-6225 2950);
PAINT ORANGE (-6225 2950);
DISPLAY INVISIBLE (-6225 2950);
FORCEPROP 1 LAST OFFPAGE TRUE
J 0
(-5700 2775);
DISPLAY 1.170213 (-5700 2775);
PAINT GREEN (-5700 2775);
DISPLAY INVISIBLE (-5700 2775);
FORCEPROP 1 LAST COMMENT_BODY TRUE
J 0
(-5925 2825);
DISPLAY 1.170213 (-5925 2825);
PAINT PEACH (-5925 2825);
DISPLAY INVISIBLE (-5925 2825);
FORCEADD OFFPAGE..5
(-6025 2850);
FORCEPROP 2 LAST $XR0 99 
J 0
(-6279 2850);
DISPLAY 0.638298 (-6279 2850);
PAINT MONO (-6279 2850);
FORCEPROP 2 LAST CDS_LIB mstr_standard
J 0
(-6025 2850);
PAINT MONO (-6025 2850);
DISPLAY INVISIBLE (-6025 2850);
FORCEPROP 2 LAST PATH I134
J 0
(-6225 2900);
DISPLAY 1.361702 (-6225 2900);
PAINT ORANGE (-6225 2900);
DISPLAY INVISIBLE (-6225 2900);
FORCEPROP 1 LAST OFFPAGE TRUE
J 0
(-5700 2725);
DISPLAY 1.170213 (-5700 2725);
PAINT GREEN (-5700 2725);
DISPLAY INVISIBLE (-5700 2725);
FORCEPROP 1 LAST COMMENT_BODY TRUE
J 0
(-5925 2775);
DISPLAY 1.170213 (-5925 2775);
PAINT PEACH (-5925 2775);
DISPLAY INVISIBLE (-5925 2775);
FORCEADD OFFPAGE..5
(-6025 2800);
FORCEPROP 2 LAST $XR0 99 
J 0
(-6279 2800);
DISPLAY 0.638298 (-6279 2800);
PAINT MONO (-6279 2800);
FORCEPROP 2 LAST CDS_LIB mstr_standard
J 0
(-6025 2800);
PAINT MONO (-6025 2800);
DISPLAY INVISIBLE (-6025 2800);
FORCEPROP 2 LAST PATH I135
J 0
(-6225 2850);
DISPLAY 1.361702 (-6225 2850);
PAINT ORANGE (-6225 2850);
DISPLAY INVISIBLE (-6225 2850);
FORCEPROP 1 LAST OFFPAGE TRUE
J 0
(-5700 2675);
DISPLAY 1.170213 (-5700 2675);
PAINT GREEN (-5700 2675);
DISPLAY INVISIBLE (-5700 2675);
FORCEPROP 1 LAST COMMENT_BODY TRUE
J 0
(-5925 2725);
DISPLAY 1.170213 (-5925 2725);
PAINT PEACH (-5925 2725);
DISPLAY INVISIBLE (-5925 2725);
FORCEADD OFFPAGE..5
(-6025 2750);
FORCEPROP 2 LAST $XR0 99 
J 0
(-6279 2750);
DISPLAY 0.638298 (-6279 2750);
PAINT MONO (-6279 2750);
FORCEPROP 2 LAST CDS_LIB mstr_standard
J 0
(-6025 2750);
PAINT MONO (-6025 2750);
DISPLAY INVISIBLE (-6025 2750);
FORCEPROP 2 LAST PATH I136
J 0
(-6225 2800);
DISPLAY 1.361702 (-6225 2800);
PAINT ORANGE (-6225 2800);
DISPLAY INVISIBLE (-6225 2800);
FORCEPROP 1 LAST OFFPAGE TRUE
J 0
(-5700 2625);
DISPLAY 1.170213 (-5700 2625);
PAINT GREEN (-5700 2625);
DISPLAY INVISIBLE (-5700 2625);
FORCEPROP 1 LAST COMMENT_BODY TRUE
J 0
(-5925 2675);
DISPLAY 1.170213 (-5925 2675);
PAINT PEACH (-5925 2675);
DISPLAY INVISIBLE (-5925 2675);
FORCEADD OFFPAGE..3
(-1850 4100);
FORCEPROP 2 LAST $XR1 166 
J 0
(-1546 4100);
DISPLAY 0.638298 (-1546 4100);
PAINT MONO (-1546 4100);
FORCEPROP 2 LAST $XR0 55 
J 0
(-1636 4100);
DISPLAY 0.638298 (-1636 4100);
PAINT MONO (-1636 4100);
FORCEPROP 2 LAST PATH I137
J 0
(-1675 4175);
DISPLAY 1.361702 (-1675 4175);
PAINT ORANGE (-1675 4175);
DISPLAY INVISIBLE (-1675 4175);
FORCEPROP 2 LAST CDS_LIB mstr_standard
J 0
(-1850 4100);
PAINT MONO (-1850 4100);
DISPLAY INVISIBLE (-1850 4100);
FORCEPROP 1 LAST OFFPAGE TRUE
J 0
(-1525 3975);
DISPLAY 1.170213 (-1525 3975);
PAINT GREEN (-1525 3975);
DISPLAY INVISIBLE (-1525 3975);
FORCEPROP 1 LAST COMMENT_BODY TRUE
J 0
(-1900 4000);
DISPLAY 1.170213 (-1900 4000);
PAINT PEACH (-1900 4000);
DISPLAY INVISIBLE (-1900 4000);
FORCEADD OFFPAGE..3
(-650 3850);
FORCEPROP 2 LAST $XR2 211 
J 0
(-196 3850);
DISPLAY 0.638298 (-196 3850);
PAINT MONO (-196 3850);
FORCEPROP 2 LAST $XR1 201 
J 0
(-316 3850);
DISPLAY 0.638298 (-316 3850);
PAINT MONO (-316 3850);
FORCEPROP 2 LAST $XR0 194 
J 0
(-436 3850);
DISPLAY 0.638298 (-436 3850);
PAINT MONO (-436 3850);
FORCEPROP 2 LAST PATH I145
J 0
(-450 3925);
DISPLAY 1.361702 (-450 3925);
PAINT ORANGE (-450 3925);
DISPLAY INVISIBLE (-450 3925);
FORCEPROP 2 LAST CDS_LIB mstr_standard
J 0
(-650 3850);
PAINT MONO (-650 3850);
DISPLAY INVISIBLE (-650 3850);
FORCEPROP 1 LAST OFFPAGE TRUE
J 0
(-325 3725);
DISPLAY 1.170213 (-325 3725);
PAINT GREEN (-325 3725);
DISPLAY INVISIBLE (-325 3725);
FORCEPROP 1 LAST COMMENT_BODY TRUE
J 0
(-700 3750);
DISPLAY 1.170213 (-700 3750);
PAINT PEACH (-700 3750);
DISPLAY INVISIBLE (-700 3750);
FORCEADD OFFPAGE..2
(-625 3800);
FORCEPROP 2 LAST $XR2 211 
J 0
(-196 3800);
DISPLAY 0.638298 (-196 3800);
PAINT MONO (-196 3800);
FORCEPROP 2 LAST $XR1 201 
J 0
(-316 3800);
DISPLAY 0.638298 (-316 3800);
PAINT MONO (-316 3800);
FORCEPROP 2 LAST $XR0 194 
J 0
(-436 3800);
DISPLAY 0.638298 (-436 3800);
PAINT MONO (-436 3800);
FORCEPROP 2 LAST CDS_LIB mstr_standard
J 0
(-625 3800);
PAINT MONO (-625 3800);
DISPLAY INVISIBLE (-625 3800);
FORCEPROP 2 LAST PATH I146
J 0
(-75 3850);
DISPLAY 1.361702 (-75 3850);
PAINT ORANGE (-75 3850);
DISPLAY INVISIBLE (-75 3850);
FORCEPROP 1 LAST OFFPAGE TRUE
J 0
(-300 3675);
DISPLAY 1.170213 (-300 3675);
PAINT GREEN (-300 3675);
DISPLAY INVISIBLE (-300 3675);
FORCEPROP 1 LAST COMMENT_BODY TRUE
J 0
(-670 3705);
DISPLAY 1.170213 (-670 3705);
PAINT PEACH (-670 3705);
DISPLAY INVISIBLE (-670 3705);
FORCEADD OFFPAGE..4
(-625 3750);
FORCEPROP 2 LAST $XR2 211 
J 0
(-199 3750);
DISPLAY 0.638298 (-199 3750);
PAINT MONO (-199 3750);
FORCEPROP 2 LAST $XR1 201 
J 0
(-319 3750);
DISPLAY 0.638298 (-319 3750);
PAINT MONO (-319 3750);
FORCEPROP 2 LAST $XR0 194 
J 0
(-439 3750);
DISPLAY 0.638298 (-439 3750);
PAINT MONO (-439 3750);
FORCEPROP 2 LAST PATH I147
J 0
(-450 3825);
DISPLAY 1.361702 (-450 3825);
PAINT ORANGE (-450 3825);
DISPLAY INVISIBLE (-450 3825);
FORCEPROP 2 LAST CDS_LIB mstr_standard
J 0
(-625 3750);
PAINT MONO (-625 3750);
DISPLAY INVISIBLE (-625 3750);
FORCEPROP 1 LAST OFFPAGE TRUE
J 0
(-300 3625);
DISPLAY 1.170213 (-300 3625);
PAINT GREEN (-300 3625);
DISPLAY INVISIBLE (-300 3625);
FORCEPROP 1 LAST COMMENT_BODY TRUE
J 0
(-650 3650);
DISPLAY 1.170213 (-650 3650);
PAINT PEACH (-650 3650);
DISPLAY INVISIBLE (-650 3650);
FORCEADD RES..1
(-2000 3750);
FORCEPROP 1 LAST LOCATION R6N10
J 0
(-2450 3750);
DISPLAY 0.617021 (-2450 3750);
PAINT AQUA (-2450 3750);
FORCEPROP 1 LAST PART_NUMBER G21796-271
J 0
(-2325 3750);
DISPLAY 0.617021 (-2325 3750);
PAINT BLUE (-2325 3750);
FORCEPROP 1 LASTPIN (-2100 3750) $PN 1
J 0
(-2088 3762);
DISPLAY 0.617021 (-2088 3762);
PAINT WHITE (-2088 3762);
FORCEPROP 1 LASTPIN (-1900 3750) $PN 2
J 0
(-1938 3762);
DISPLAY 0.617021 (-1938 3762);
PAINT WHITE (-1938 3762);
FORCEPROP 1 LAST PACK_TYPE 0402
J 0
(-1700 3750);
DISPLAY 0.617021 (-1700 3750);
PAINT SKYBLUE (-1700 3750);
FORCEPROP 1 LAST VALUE 221
J 0
(-1875 3750);
DISPLAY 0.617021 (-1875 3750);
PAINT SKYBLUE (-1875 3750);
FORCEPROP 1 LAST TOLERANCE 1.0%
J 0
(-1800 3750);
DISPLAY 0.617021 (-1800 3750);
PAINT SKYBLUE (-1800 3750);
FORCEPROP 1 LAST WATTAGE 1/16W
J 0
(-1600 3750);
DISPLAY 0.510638 (-1600 3750);
PAINT SKYBLUE (-1600 3750);
FORCEPROP 2 LAST CDS_LOCATION R6N10
J 0
(-2475 3750);
DISPLAY 0.617021 (-2475 3750);
PAINT AQUA (-2475 3750);
DISPLAY INVISIBLE (-2475 3750);
FORCEPROP 2 LAST BOM_COST PROC_SIDEBAND
J 0
(-2000 3750);
PAINT MONO (-2000 3750);
DISPLAY INVISIBLE (-2000 3750);
FORCEPROP 2 LAST CDS_LIB mstr_discrete
J 0
(-2000 3750);
DISPLAY 1.340426 (-2000 3750);
PAINT ORANGE (-2000 3750);
DISPLAY INVISIBLE (-2000 3750);
FORCEPROP 1 LAST MATERIAL CHIP
J 0
(-1850 3650);
DISPLAY 0.510638 (-1850 3650);
PAINT SKYBLUE (-1850 3650);
DISPLAY INVISIBLE (-1850 3650);
FORCEPROP 2 LAST ROOM CPU0
J 0
(-2050 3900);
PAINT PEACH (-2050 3900);
DISPLAY INVISIBLE (-2050 3900);
FORCEPROP 1 LAST PATH I149
J 0
(-2050 3900);
DISPLAY 1.319149 (-2050 3900);
PAINT WHITE (-2050 3900);
DISPLAY INVISIBLE (-2050 3900);
FORCEPROP 2 LAST SEC 1
J 0
(-2050 3975);
DISPLAY 0.680851 (-2050 3975);
PAINT MONO (-2050 3975);
DISPLAY INVISIBLE (-2050 3975);
FORCEPROP 2 LAST SEC_TYPE 0402
J 0
(-2050 3975);
DISPLAY 1.021277 (-2050 3975);
PAINT ORANGE (-2050 3975);
DISPLAY INVISIBLE (-2050 3975);
FORCEADD OFFPAGE..5
(-6350 3500);
FORCEPROP 2 LAST $XR0 98 
J 0
(-6574 3500);
DISPLAY 0.638298 (-6574 3500);
PAINT MONO (-6574 3500);
FORCEPROP 2 LAST PATH I15
J 0
(-6300 3575);
DISPLAY 1.361702 (-6300 3575);
PAINT ORANGE (-6300 3575);
DISPLAY INVISIBLE (-6300 3575);
FORCEPROP 2 LAST CDS_LIB mstr_standard
J 0
(-6350 3500);
PAINT MONO (-6350 3500);
DISPLAY INVISIBLE (-6350 3500);
FORCEPROP 1 LAST OFFPAGE TRUE
J 0
(-6025 3375);
DISPLAY 1.170213 (-6025 3375);
PAINT GREEN (-6025 3375);
DISPLAY INVISIBLE (-6025 3375);
FORCEPROP 1 LAST COMMENT_BODY TRUE
J 0
(-6250 3425);
DISPLAY 1.170213 (-6250 3425);
PAINT PEACH (-6250 3425);
DISPLAY INVISIBLE (-6250 3425);
FORCEADD RES..1
(-2000 3800);
FORCEPROP 1 LAST LOCATION R6N12
J 0
(-2450 3800);
DISPLAY 0.617021 (-2450 3800);
PAINT AQUA (-2450 3800);
FORCEPROP 1 LASTPIN (-2100 3800) $PN 1
J 0
(-2088 3812);
DISPLAY 0.617021 (-2088 3812);
PAINT WHITE (-2088 3812);
FORCEPROP 1 LAST PACK_TYPE 0402
J 0
(-1700 3800);
DISPLAY 0.617021 (-1700 3800);
PAINT SKYBLUE (-1700 3800);
FORCEPROP 1 LAST TOLERANCE 5%
J 0
(-1800 3800);
DISPLAY 0.617021 (-1800 3800);
PAINT SKYBLUE (-1800 3800);
FORCEPROP 1 LAST PART_NUMBER G21497-005
J 0
(-2325 3800);
DISPLAY 0.617021 (-2325 3800);
PAINT BLUE (-2325 3800);
FORCEPROP 1 LASTPIN (-1900 3800) $PN 2
J 0
(-1938 3812);
DISPLAY 0.617021 (-1938 3812);
PAINT WHITE (-1938 3812);
FORCEPROP 1 LAST VALUE 0.0
J 0
(-1875 3800);
DISPLAY 0.617021 (-1875 3800);
PAINT SKYBLUE (-1875 3800);
FORCEPROP 1 LAST WATTAGE 1/16W
J 0
(-1600 3800);
DISPLAY 0.510638 (-1600 3800);
PAINT SKYBLUE (-1600 3800);
FORCEPROP 2 LAST SEC_TYPE 0402
J 0
(-2050 4025);
DISPLAY 1.021277 (-2050 4025);
PAINT ORANGE (-2050 4025);
DISPLAY INVISIBLE (-2050 4025);
FORCEPROP 2 LAST SEC 1
J 0
(-2050 4025);
DISPLAY 0.680851 (-2050 4025);
PAINT MONO (-2050 4025);
DISPLAY INVISIBLE (-2050 4025);
FORCEPROP 1 LAST PATH I150
J 0
(-2050 3950);
DISPLAY 1.319149 (-2050 3950);
PAINT WHITE (-2050 3950);
DISPLAY INVISIBLE (-2050 3950);
FORCEPROP 2 LAST ROOM CPU0
J 0
(-2050 3950);
PAINT PEACH (-2050 3950);
DISPLAY INVISIBLE (-2050 3950);
FORCEPROP 2 LAST CDS_LIB mstr_discrete
J 0
(-2000 3800);
DISPLAY 1.340426 (-2000 3800);
PAINT ORANGE (-2000 3800);
DISPLAY INVISIBLE (-2000 3800);
FORCEPROP 2 LAST BOM_COST PROC_SIDEBAND
J 0
(-2000 3800);
PAINT MONO (-2000 3800);
DISPLAY INVISIBLE (-2000 3800);
FORCEPROP 1 LAST MATERIAL CHIP
J 0
(-1850 3700);
DISPLAY 0.510638 (-1850 3700);
PAINT SKYBLUE (-1850 3700);
DISPLAY INVISIBLE (-1850 3700);
FORCEPROP 2 LAST CDS_LOCATION R6N12
J 0
(-2475 3800);
DISPLAY 0.617021 (-2475 3800);
PAINT AQUA (-2475 3800);
DISPLAY INVISIBLE (-2475 3800);
FORCEADD RES..1
(-2000 3850);
FORCEPROP 1 LAST PART_NUMBER G21497-005
J 0
(-2325 3850);
DISPLAY 0.617021 (-2325 3850);
PAINT BLUE (-2325 3850);
FORCEPROP 1 LAST LOCATION R6N11
J 0
(-2450 3850);
DISPLAY 0.617021 (-2450 3850);
PAINT AQUA (-2450 3850);
FORCEPROP 1 LAST TOLERANCE 5%
J 0
(-1800 3850);
DISPLAY 0.617021 (-1800 3850);
PAINT SKYBLUE (-1800 3850);
FORCEPROP 1 LAST PACK_TYPE 0402
J 0
(-1700 3850);
DISPLAY 0.617021 (-1700 3850);
PAINT SKYBLUE (-1700 3850);
FORCEPROP 1 LASTPIN (-1900 3850) $PN 2
J 0
(-1938 3862);
DISPLAY 0.617021 (-1938 3862);
PAINT WHITE (-1938 3862);
FORCEPROP 1 LASTPIN (-2100 3850) $PN 1
J 0
(-2088 3862);
DISPLAY 0.617021 (-2088 3862);
PAINT WHITE (-2088 3862);
FORCEPROP 1 LAST WATTAGE 1/16W
J 0
(-1600 3850);
DISPLAY 0.510638 (-1600 3850);
PAINT SKYBLUE (-1600 3850);
FORCEPROP 1 LAST VALUE 0.0
J 0
(-1875 3850);
DISPLAY 0.617021 (-1875 3850);
PAINT SKYBLUE (-1875 3850);
FORCEPROP 2 LAST SEC_TYPE 0402
J 0
(-2050 4075);
DISPLAY 1.021277 (-2050 4075);
PAINT ORANGE (-2050 4075);
DISPLAY INVISIBLE (-2050 4075);
FORCEPROP 2 LAST SEC 1
J 0
(-2050 4075);
DISPLAY 0.680851 (-2050 4075);
PAINT MONO (-2050 4075);
DISPLAY INVISIBLE (-2050 4075);
FORCEPROP 1 LAST PATH I151
J 0
(-2050 4000);
DISPLAY 1.319149 (-2050 4000);
PAINT WHITE (-2050 4000);
DISPLAY INVISIBLE (-2050 4000);
FORCEPROP 2 LAST ROOM CPU0
J 0
(-2050 4000);
PAINT PEACH (-2050 4000);
DISPLAY INVISIBLE (-2050 4000);
FORCEPROP 2 LAST CDS_LIB mstr_discrete
J 0
(-2000 3850);
DISPLAY 1.340426 (-2000 3850);
PAINT ORANGE (-2000 3850);
DISPLAY INVISIBLE (-2000 3850);
FORCEPROP 2 LAST BOM_COST PROC_SIDEBAND
J 0
(-2000 3850);
PAINT MONO (-2000 3850);
DISPLAY INVISIBLE (-2000 3850);
FORCEPROP 1 LAST MATERIAL CHIP
J 0
(-1850 3750);
DISPLAY 0.510638 (-1850 3750);
PAINT SKYBLUE (-1850 3750);
DISPLAY INVISIBLE (-1850 3750);
FORCEPROP 2 LAST CDS_LOCATION R6N11
J 0
(-2475 3850);
DISPLAY 0.617021 (-2475 3850);
PAINT AQUA (-2475 3850);
DISPLAY INVISIBLE (-2475 3850);
FORCEADD RES..1
(-2000 3900);
FORCEPROP 1 LASTPIN (-2100 3900) $PN 1
J 0
(-2088 3912);
DISPLAY 0.617021 (-2088 3912);
PAINT WHITE (-2088 3912);
FORCEPROP 1 LAST PACK_TYPE 0402
J 0
(-1700 3900);
DISPLAY 0.617021 (-1700 3900);
PAINT SKYBLUE (-1700 3900);
FORCEPROP 1 LAST LOCATION R6B3
J 0
(-2450 3900);
DISPLAY 0.617021 (-2450 3900);
PAINT AQUA (-2450 3900);
FORCEPROP 1 LAST PART_NUMBER G21796-271
J 0
(-2325 3900);
DISPLAY 0.617021 (-2325 3900);
PAINT BLUE (-2325 3900);
FORCEPROP 1 LASTPIN (-1900 3900) $PN 2
J 0
(-1938 3912);
DISPLAY 0.617021 (-1938 3912);
PAINT WHITE (-1938 3912);
FORCEPROP 1 LAST WATTAGE 1/16W
J 0
(-1600 3900);
DISPLAY 0.510638 (-1600 3900);
PAINT SKYBLUE (-1600 3900);
FORCEPROP 1 LAST TOLERANCE 1.0%
J 0
(-1800 3900);
DISPLAY 0.617021 (-1800 3900);
PAINT SKYBLUE (-1800 3900);
FORCEPROP 1 LAST VALUE 221
J 0
(-1875 3900);
DISPLAY 0.617021 (-1875 3900);
PAINT SKYBLUE (-1875 3900);
FORCEPROP 2 LAST CDS_LOCATION R6B3
J 0
(-2475 3900);
DISPLAY 0.617021 (-2475 3900);
PAINT AQUA (-2475 3900);
DISPLAY INVISIBLE (-2475 3900);
FORCEPROP 2 LAST CDS_LIB mstr_discrete
J 0
(-2000 3900);
DISPLAY 1.340426 (-2000 3900);
PAINT ORANGE (-2000 3900);
DISPLAY INVISIBLE (-2000 3900);
FORCEPROP 2 LAST BOM_COST PROC_SIDEBAND
J 0
(-2000 3900);
PAINT MONO (-2000 3900);
DISPLAY INVISIBLE (-2000 3900);
FORCEPROP 2 LAST ROOM CPU0
J 0
(-2050 4050);
PAINT PEACH (-2050 4050);
DISPLAY INVISIBLE (-2050 4050);
FORCEPROP 1 LAST PATH I152
J 0
(-2050 4050);
DISPLAY 1.319149 (-2050 4050);
PAINT WHITE (-2050 4050);
DISPLAY INVISIBLE (-2050 4050);
FORCEPROP 2 LAST SEC_TYPE 0402
J 0
(-2050 4125);
DISPLAY 1.021277 (-2050 4125);
PAINT ORANGE (-2050 4125);
DISPLAY INVISIBLE (-2050 4125);
FORCEPROP 2 LAST SEC 1
J 0
(-2050 4125);
DISPLAY 0.680851 (-2050 4125);
PAINT MONO (-2050 4125);
DISPLAY INVISIBLE (-2050 4125);
FORCEPROP 1 LAST MATERIAL CHIP
J 0
(-2025 3900);
DISPLAY 0.510638 (-2025 3900);
PAINT SKYBLUE (-2025 3900);
DISPLAY INVISIBLE (-2025 3900);
FORCEADD RES..1
(-2000 3950);
FORCEPROP 1 LASTPIN (-2100 3950) $PN 1
J 0
(-2088 3962);
DISPLAY 0.617021 (-2088 3962);
PAINT WHITE (-2088 3962);
FORCEPROP 1 LAST PACK_TYPE 0402
J 0
(-1700 3950);
DISPLAY 0.617021 (-1700 3950);
PAINT SKYBLUE (-1700 3950);
FORCEPROP 1 LAST PART_NUMBER G21497-005
J 0
(-2325 3950);
DISPLAY 0.617021 (-2325 3950);
PAINT BLUE (-2325 3950);
FORCEPROP 1 LAST LOCATION R6B5
J 0
(-2450 3950);
DISPLAY 0.617021 (-2450 3950);
PAINT AQUA (-2450 3950);
FORCEPROP 1 LAST TOLERANCE 5%
J 0
(-1800 3950);
DISPLAY 0.617021 (-1800 3950);
PAINT SKYBLUE (-1800 3950);
FORCEPROP 1 LASTPIN (-1900 3950) $PN 2
J 0
(-1938 3962);
DISPLAY 0.617021 (-1938 3962);
PAINT WHITE (-1938 3962);
FORCEPROP 1 LAST VALUE 0.0
J 0
(-1875 3950);
DISPLAY 0.617021 (-1875 3950);
PAINT SKYBLUE (-1875 3950);
FORCEPROP 1 LAST WATTAGE 1/16W
J 0
(-1600 3950);
DISPLAY 0.510638 (-1600 3950);
PAINT SKYBLUE (-1600 3950);
FORCEPROP 2 LAST CDS_LOCATION R6B5
J 0
(-2475 3950);
DISPLAY 0.617021 (-2475 3950);
PAINT AQUA (-2475 3950);
DISPLAY INVISIBLE (-2475 3950);
FORCEPROP 2 LAST CDS_LIB mstr_discrete
J 0
(-2000 3950);
DISPLAY 1.340426 (-2000 3950);
PAINT ORANGE (-2000 3950);
DISPLAY INVISIBLE (-2000 3950);
FORCEPROP 2 LAST BOM_COST PROC_SIDEBAND
J 0
(-2000 3950);
PAINT MONO (-2000 3950);
DISPLAY INVISIBLE (-2000 3950);
FORCEPROP 1 LAST MATERIAL CHIP
J 0
(-1850 3850);
DISPLAY 0.510638 (-1850 3850);
PAINT SKYBLUE (-1850 3850);
DISPLAY INVISIBLE (-1850 3850);
FORCEPROP 2 LAST SEC_TYPE 0402
J 0
(-2050 4175);
DISPLAY 1.021277 (-2050 4175);
PAINT ORANGE (-2050 4175);
DISPLAY INVISIBLE (-2050 4175);
FORCEPROP 2 LAST SEC 1
J 0
(-2050 4175);
DISPLAY 0.680851 (-2050 4175);
PAINT MONO (-2050 4175);
DISPLAY INVISIBLE (-2050 4175);
FORCEPROP 1 LAST PATH I153
J 0
(-2050 4100);
DISPLAY 1.319149 (-2050 4100);
PAINT WHITE (-2050 4100);
DISPLAY INVISIBLE (-2050 4100);
FORCEPROP 2 LAST ROOM CPU0
J 0
(-2050 4100);
PAINT PEACH (-2050 4100);
DISPLAY INVISIBLE (-2050 4100);
FORCEADD RES..1
(-2000 4000);
FORCEPROP 1 LAST TOLERANCE 5%
J 0
(-1800 4000);
DISPLAY 0.617021 (-1800 4000);
PAINT SKYBLUE (-1800 4000);
FORCEPROP 1 LASTPIN (-2100 4000) $PN 1
J 0
(-2088 4012);
DISPLAY 0.617021 (-2088 4012);
PAINT WHITE (-2088 4012);
FORCEPROP 1 LASTPIN (-1900 4000) $PN 2
J 0
(-1938 4012);
DISPLAY 0.617021 (-1938 4012);
PAINT WHITE (-1938 4012);
FORCEPROP 1 LAST LOCATION R6B4
J 0
(-2450 4000);
DISPLAY 0.617021 (-2450 4000);
PAINT AQUA (-2450 4000);
FORCEPROP 1 LAST PART_NUMBER G21497-005
J 0
(-2325 4000);
DISPLAY 0.617021 (-2325 4000);
PAINT BLUE (-2325 4000);
FORCEPROP 1 LAST VALUE 0.0
J 0
(-1875 4000);
DISPLAY 0.617021 (-1875 4000);
PAINT SKYBLUE (-1875 4000);
FORCEPROP 1 LAST PACK_TYPE 0402
J 0
(-1700 4000);
DISPLAY 0.617021 (-1700 4000);
PAINT SKYBLUE (-1700 4000);
FORCEPROP 1 LAST WATTAGE 1/16W
J 0
(-1600 4000);
DISPLAY 0.510638 (-1600 4000);
PAINT SKYBLUE (-1600 4000);
FORCEPROP 2 LAST CDS_LOCATION R6B4
J 0
(-2475 4000);
DISPLAY 0.617021 (-2475 4000);
PAINT AQUA (-2475 4000);
DISPLAY INVISIBLE (-2475 4000);
FORCEPROP 2 LAST CDS_LIB mstr_discrete
J 0
(-2000 4000);
DISPLAY 1.340426 (-2000 4000);
PAINT ORANGE (-2000 4000);
DISPLAY INVISIBLE (-2000 4000);
FORCEPROP 2 LAST BOM_COST PROC_SIDEBAND
J 0
(-2000 4000);
PAINT MONO (-2000 4000);
DISPLAY INVISIBLE (-2000 4000);
FORCEPROP 1 LAST MATERIAL CHIP
J 0
(-1850 3900);
DISPLAY 0.510638 (-1850 3900);
PAINT SKYBLUE (-1850 3900);
DISPLAY INVISIBLE (-1850 3900);
FORCEPROP 1 LAST PATH I154
J 0
(-2050 4150);
DISPLAY 1.319149 (-2050 4150);
PAINT WHITE (-2050 4150);
DISPLAY INVISIBLE (-2050 4150);
FORCEPROP 2 LAST ROOM CPU0
J 0
(-2050 4150);
PAINT PEACH (-2050 4150);
DISPLAY INVISIBLE (-2050 4150);
FORCEPROP 2 LAST SEC_TYPE 0402
J 0
(-2050 4225);
DISPLAY 1.021277 (-2050 4225);
PAINT ORANGE (-2050 4225);
DISPLAY INVISIBLE (-2050 4225);
FORCEPROP 2 LAST SEC 1
J 0
(-2050 4225);
DISPLAY 0.680851 (-2050 4225);
PAINT MONO (-2050 4225);
DISPLAY INVISIBLE (-2050 4225);
FORCEADD OFFPAGE..3
(-650 4000);
FORCEPROP 2 LAST $XR2 218 
J 0
(-196 4000);
DISPLAY 0.638298 (-196 4000);
PAINT MONO (-196 4000);
FORCEPROP 2 LAST $XR1 215 
J 0
(-316 4000);
DISPLAY 0.638298 (-316 4000);
PAINT MONO (-316 4000);
FORCEPROP 2 LAST $XR0 194 
J 0
(-436 4000);
DISPLAY 0.638298 (-436 4000);
PAINT MONO (-436 4000);
FORCEPROP 2 LAST PATH I155
J 0
(-450 4075);
DISPLAY 1.361702 (-450 4075);
PAINT ORANGE (-450 4075);
DISPLAY INVISIBLE (-450 4075);
FORCEPROP 2 LAST CDS_LIB mstr_standard
J 0
(-650 4000);
PAINT MONO (-650 4000);
DISPLAY INVISIBLE (-650 4000);
FORCEPROP 1 LAST OFFPAGE TRUE
J 0
(-325 3875);
DISPLAY 1.170213 (-325 3875);
PAINT GREEN (-325 3875);
DISPLAY INVISIBLE (-325 3875);
FORCEPROP 1 LAST COMMENT_BODY TRUE
J 0
(-700 3900);
DISPLAY 1.170213 (-700 3900);
PAINT PEACH (-700 3900);
DISPLAY INVISIBLE (-700 3900);
FORCEADD OFFPAGE..2
(-625 3950);
FORCEPROP 2 LAST $XR2 218 
J 0
(-196 3950);
DISPLAY 0.638298 (-196 3950);
PAINT MONO (-196 3950);
FORCEPROP 2 LAST $XR1 215 
J 0
(-316 3950);
DISPLAY 0.638298 (-316 3950);
PAINT MONO (-316 3950);
FORCEPROP 2 LAST $XR0 194 
J 0
(-436 3950);
DISPLAY 0.638298 (-436 3950);
PAINT MONO (-436 3950);
FORCEPROP 2 LAST PATH I156
J 0
(-450 4025);
DISPLAY 1.361702 (-450 4025);
PAINT ORANGE (-450 4025);
DISPLAY INVISIBLE (-450 4025);
FORCEPROP 2 LAST CDS_LIB mstr_standard
J 0
(-625 3950);
PAINT MONO (-625 3950);
DISPLAY INVISIBLE (-625 3950);
FORCEPROP 1 LAST OFFPAGE TRUE
J 0
(-300 3825);
DISPLAY 1.170213 (-300 3825);
PAINT GREEN (-300 3825);
DISPLAY INVISIBLE (-300 3825);
FORCEPROP 1 LAST COMMENT_BODY TRUE
J 0
(-670 3855);
DISPLAY 1.170213 (-670 3855);
PAINT PEACH (-670 3855);
DISPLAY INVISIBLE (-670 3855);
FORCEADD OFFPAGE..4
(-625 3900);
FORCEPROP 2 LAST $XR2 218 
J 0
(-199 3900);
DISPLAY 0.638298 (-199 3900);
PAINT MONO (-199 3900);
FORCEPROP 2 LAST $XR1 215 
J 0
(-319 3900);
DISPLAY 0.638298 (-319 3900);
PAINT MONO (-319 3900);
FORCEPROP 2 LAST $XR0 194 
J 0
(-439 3900);
DISPLAY 0.638298 (-439 3900);
PAINT MONO (-439 3900);
FORCEPROP 2 LAST PATH I157
J 0
(-450 3975);
DISPLAY 1.361702 (-450 3975);
PAINT ORANGE (-450 3975);
DISPLAY INVISIBLE (-450 3975);
FORCEPROP 2 LAST CDS_LIB mstr_standard
J 0
(-625 3900);
PAINT MONO (-625 3900);
DISPLAY INVISIBLE (-625 3900);
FORCEPROP 1 LAST OFFPAGE TRUE
J 0
(-300 3775);
DISPLAY 1.170213 (-300 3775);
PAINT GREEN (-300 3775);
DISPLAY INVISIBLE (-300 3775);
FORCEPROP 1 LAST COMMENT_BODY TRUE
J 0
(-650 3800);
DISPLAY 1.170213 (-650 3800);
PAINT PEACH (-650 3800);
DISPLAY INVISIBLE (-650 3800);
FORCEADD PVCCIO_CPU0..1
(-900 4650);
FORCEPROP 3 LASTPIN (-900 4600) SIG_NAME PVCCIO_CPU0\g
J 0
(-890 4610);
DISPLAY 0.659574 (-890 4610);
PAINT MONO (-890 4610);
DISPLAY INVISIBLE (-890 4610);
FORCEPROP 1 LAST PATH I158
J 0
(-850 4675);
DISPLAY 0.872340 (-850 4675);
PAINT AQUA (-850 4675);
DISPLAY INVISIBLE (-850 4675);
FORCEPROP 2 LAST CDS_LIB mstr_symbols
J 0
(-900 4650);
PAINT ORANGE (-900 4650);
DISPLAY INVISIBLE (-900 4650);
FORCEPROP 1 LAST VOLTAGE 1.1V
J 0
(-945 4607);
DISPLAY 0.340426 (-945 4607);
PAINT SKYBLUE (-945 4607);
DISPLAY INVISIBLE (-945 4607);
FORCEPROP 1 LAST BODY_TYPE PLUMBING
J 0
(-945 4607);
DISPLAY 0.340426 (-945 4607);
PAINT GREEN (-945 4607);
DISPLAY INVISIBLE (-945 4607);
FORCEPROP 1 LAST HDL_POWER PVCCIO_CPU0
J 1
(-900 4700);
DISPLAY 0.872340 (-900 4700);
PAINT GREEN (-900 4700);
DISPLAY INVISIBLE (-900 4700);
FORCEADD RES..2
(-1000 4300);
FORCEPROP 1 LAST PACK_TYPE 0402
J 0
(-960 4125);
DISPLAY 0.638298 (-960 4125);
PAINT SKYBLUE (-960 4125);
FORCEPROP 1 LAST WATTAGE 1/16W
J 0
(-960 4275);
DISPLAY 0.638298 (-960 4275);
PAINT SKYBLUE (-960 4275);
FORCEPROP 1 LAST TOLERANCE 1%
J 0
(-955 4325);
DISPLAY 0.638298 (-955 4325);
PAINT SKYBLUE (-955 4325);
FORCEPROP 1 LASTPIN (-1000 4200) $PN 2
J 0
(-995 4210);
DISPLAY 0.617021 (-995 4210);
PAINT WHITE (-995 4210);
FORCEPROP 1 LAST PART_NUMBER G21796-017
J 0
(-960 4175);
DISPLAY 0.617021 (-960 4175);
PAINT BLUE (-960 4175);
FORCEPROP 1 LAST MATERIAL CHIP
J 0
(-960 4225);
DISPLAY 0.617021 (-960 4225);
PAINT SKYBLUE (-960 4225);
FORCEPROP 1 LASTPIN (-1000 4400) $PN 1
J 0
(-995 4362);
DISPLAY 0.617021 (-995 4362);
PAINT WHITE (-995 4362);
FORCEPROP 1 LAST VALUE 100.0
J 0
(-955 4375);
DISPLAY 0.617021 (-955 4375);
PAINT SKYBLUE (-955 4375);
FORCEPROP 1 LAST LOCATION R6B2
J 0
(-955 4425);
DISPLAY 0.617021 (-955 4425);
PAINT AQUA (-955 4425);
FORCEPROP 2 LAST CDS_LOCATION R6B2
J 0
(-955 4425);
DISPLAY 0.617021 (-955 4425);
PAINT AQUA (-955 4425);
DISPLAY INVISIBLE (-955 4425);
FORCEPROP 1 LAST PATH I159
J 0
(-950 4475);
DISPLAY 1.319149 (-950 4475);
PAINT WHITE (-950 4475);
DISPLAY INVISIBLE (-950 4475);
FORCEPROP 2 LAST SEC_TYPE 0402
J 0
(-950 4550);
DISPLAY 1.021277 (-950 4550);
PAINT ORANGE (-950 4550);
DISPLAY INVISIBLE (-950 4550);
FORCEPROP 2 LAST SEC 1
J 0
(-950 4550);
DISPLAY 0.680851 (-950 4550);
PAINT MONO (-950 4550);
DISPLAY INVISIBLE (-950 4550);
FORCEPROP 2 LAST CDS_LIB mstr_discrete
J 0
(-1000 4300);
PAINT ORANGE (-1000 4300);
DISPLAY INVISIBLE (-1000 4300);
FORCEPROP 2 LAST BOM_COST PROC_SIDEBAND
J 0
(-1000 4300);
PAINT MONO (-1000 4300);
DISPLAY INVISIBLE (-1000 4300);
FORCEPROP 2 LAST ROOM CPU0
J 0
(-975 4075);
PAINT ORANGE (-975 4075);
DISPLAY INVISIBLE (-975 4075);
FORCEADD RES..2
(-750 4300);
FORCEPROP 1 LAST VALUE 49.9
J 0
(-705 4375);
DISPLAY 0.617021 (-705 4375);
PAINT SKYBLUE (-705 4375);
FORCEPROP 1 LAST PART_NUMBER G21796-047
J 0
(-710 4175);
DISPLAY 0.617021 (-710 4175);
PAINT BLUE (-710 4175);
FORCEPROP 1 LAST PACK_TYPE 0402
J 0
(-710 4125);
DISPLAY 0.638298 (-710 4125);
PAINT SKYBLUE (-710 4125);
FORCEPROP 1 LASTPIN (-750 4400) $PN 1
J 0
(-745 4362);
DISPLAY 0.617021 (-745 4362);
PAINT WHITE (-745 4362);
FORCEPROP 1 LAST LOCATION R6B1
J 0
(-705 4425);
DISPLAY 0.617021 (-705 4425);
PAINT AQUA (-705 4425);
FORCEPROP 1 LAST WATTAGE 1/16W
J 0
(-710 4275);
DISPLAY 0.638298 (-710 4275);
PAINT SKYBLUE (-710 4275);
FORCEPROP 1 LAST TOLERANCE 1%
J 0
(-705 4325);
DISPLAY 0.638298 (-705 4325);
PAINT SKYBLUE (-705 4325);
FORCEPROP 1 LAST MATERIAL CHIP
J 0
(-710 4225);
DISPLAY 0.617021 (-710 4225);
PAINT SKYBLUE (-710 4225);
FORCEPROP 1 LASTPIN (-750 4200) $PN 2
J 0
(-745 4210);
DISPLAY 0.617021 (-745 4210);
PAINT WHITE (-745 4210);
FORCEPROP 2 LAST SEC 1
J 0
(-700 4550);
DISPLAY 0.680851 (-700 4550);
PAINT MONO (-700 4550);
DISPLAY INVISIBLE (-700 4550);
FORCEPROP 2 LAST CDS_LOCATION R6B1
J 0
(-705 4425);
DISPLAY 0.617021 (-705 4425);
PAINT AQUA (-705 4425);
DISPLAY INVISIBLE (-705 4425);
FORCEPROP 1 LAST PATH I161
J 0
(-700 4475);
DISPLAY 1.319149 (-700 4475);
PAINT WHITE (-700 4475);
DISPLAY INVISIBLE (-700 4475);
FORCEPROP 2 LAST SEC_TYPE 0402
J 0
(-700 4550);
DISPLAY 1.021277 (-700 4550);
PAINT ORANGE (-700 4550);
DISPLAY INVISIBLE (-700 4550);
FORCEPROP 2 LAST BOM_COST PROC_SIDEBAND
J 0
(-750 4300);
PAINT MONO (-750 4300);
DISPLAY INVISIBLE (-750 4300);
FORCEPROP 2 LAST CDS_LIB mstr_discrete
J 0
(-750 4300);
PAINT ORANGE (-750 4300);
DISPLAY INVISIBLE (-750 4300);
FORCEPROP 2 LAST ROOM CPU0
J 0
(-725 4075);
PAINT ORANGE (-725 4075);
DISPLAY INVISIBLE (-725 4075);
FORCEADD RES..2
(-1000 3500);
FORCEPROP 1 LAST PACK_TYPE 0402
J 0
(-960 3325);
DISPLAY 0.638298 (-960 3325);
PAINT SKYBLUE (-960 3325);
FORCEPROP 1 LAST PART_NUMBER G21796-017
J 0
(-960 3375);
DISPLAY 0.617021 (-960 3375);
PAINT BLUE (-960 3375);
FORCEPROP 1 LAST MATERIAL CHIP
J 0
(-960 3425);
DISPLAY 0.617021 (-960 3425);
PAINT SKYBLUE (-960 3425);
FORCEPROP 1 LAST WATTAGE 1/16W
J 0
(-960 3475);
DISPLAY 0.638298 (-960 3475);
PAINT SKYBLUE (-960 3475);
FORCEPROP 1 LAST LOCATION R6N2
J 0
(-955 3625);
DISPLAY 0.617021 (-955 3625);
PAINT AQUA (-955 3625);
FORCEPROP 1 LASTPIN (-1000 3400) $PN 2
J 0
(-995 3410);
DISPLAY 0.617021 (-995 3410);
PAINT WHITE (-995 3410);
FORCEPROP 1 LASTPIN (-1000 3600) $PN 1
J 0
(-995 3562);
DISPLAY 0.617021 (-995 3562);
PAINT WHITE (-995 3562);
FORCEPROP 1 LAST VALUE 100.0
J 0
(-955 3575);
DISPLAY 0.617021 (-955 3575);
PAINT SKYBLUE (-955 3575);
FORCEPROP 1 LAST TOLERANCE 1%
J 0
(-955 3525);
DISPLAY 0.638298 (-955 3525);
PAINT SKYBLUE (-955 3525);
FORCEPROP 2 LAST SEC_TYPE 0402
J 0
(-950 3750);
DISPLAY 1.021277 (-950 3750);
PAINT ORANGE (-950 3750);
DISPLAY INVISIBLE (-950 3750);
FORCEPROP 2 LAST SEC 1
J 0
(-950 3750);
DISPLAY 0.680851 (-950 3750);
PAINT MONO (-950 3750);
DISPLAY INVISIBLE (-950 3750);
FORCEPROP 2 LAST CDS_LOCATION R6N2
J 0
(-955 3625);
DISPLAY 0.617021 (-955 3625);
PAINT AQUA (-955 3625);
DISPLAY INVISIBLE (-955 3625);
FORCEPROP 1 LAST PATH I163
J 0
(-950 3675);
DISPLAY 1.319149 (-950 3675);
PAINT WHITE (-950 3675);
DISPLAY INVISIBLE (-950 3675);
FORCEPROP 2 LAST BOM_COST PROC_SIDEBAND
J 0
(-1000 3500);
PAINT MONO (-1000 3500);
DISPLAY INVISIBLE (-1000 3500);
FORCEPROP 2 LAST CDS_LIB mstr_discrete
J 0
(-1000 3500);
PAINT ORANGE (-1000 3500);
DISPLAY INVISIBLE (-1000 3500);
FORCEPROP 2 LAST ROOM CPU0
J 0
(-975 3275);
PAINT ORANGE (-975 3275);
DISPLAY INVISIBLE (-975 3275);
FORCEADD RES..2
(-750 3500);
FORCEPROP 1 LAST VALUE 49.9
J 0
(-705 3575);
DISPLAY 0.617021 (-705 3575);
PAINT SKYBLUE (-705 3575);
FORCEPROP 1 LAST TOLERANCE 1%
J 0
(-705 3525);
DISPLAY 0.638298 (-705 3525);
PAINT SKYBLUE (-705 3525);
FORCEPROP 1 LAST LOCATION R6N1
J 0
(-705 3625);
DISPLAY 0.617021 (-705 3625);
PAINT AQUA (-705 3625);
FORCEPROP 1 LAST WATTAGE 1/16W
J 0
(-710 3475);
DISPLAY 0.638298 (-710 3475);
PAINT SKYBLUE (-710 3475);
FORCEPROP 1 LAST MATERIAL CHIP
J 0
(-710 3425);
DISPLAY 0.617021 (-710 3425);
PAINT SKYBLUE (-710 3425);
FORCEPROP 1 LAST PACK_TYPE 0402
J 0
(-710 3325);
DISPLAY 0.638298 (-710 3325);
PAINT SKYBLUE (-710 3325);
FORCEPROP 1 LASTPIN (-750 3400) $PN 2
J 0
(-745 3410);
DISPLAY 0.617021 (-745 3410);
PAINT WHITE (-745 3410);
FORCEPROP 1 LASTPIN (-750 3600) $PN 1
J 0
(-745 3562);
DISPLAY 0.617021 (-745 3562);
PAINT WHITE (-745 3562);
FORCEPROP 1 LAST PART_NUMBER G21796-047
J 0
(-710 3375);
DISPLAY 0.617021 (-710 3375);
PAINT BLUE (-710 3375);
FORCEPROP 1 LAST PATH I164
J 0
(-700 3675);
DISPLAY 1.319149 (-700 3675);
PAINT WHITE (-700 3675);
DISPLAY INVISIBLE (-700 3675);
FORCEPROP 2 LAST SEC_TYPE 0402
J 0
(-700 3750);
DISPLAY 1.021277 (-700 3750);
PAINT ORANGE (-700 3750);
DISPLAY INVISIBLE (-700 3750);
FORCEPROP 2 LAST SEC 1
J 0
(-700 3750);
DISPLAY 0.680851 (-700 3750);
PAINT MONO (-700 3750);
DISPLAY INVISIBLE (-700 3750);
FORCEPROP 2 LAST CDS_LOCATION R6N1
J 0
(-705 3600);
DISPLAY 0.617021 (-705 3600);
PAINT AQUA (-705 3600);
DISPLAY INVISIBLE (-705 3600);
FORCEPROP 2 LAST CDS_LIB mstr_discrete
J 0
(-750 3500);
PAINT ORANGE (-750 3500);
DISPLAY INVISIBLE (-750 3500);
FORCEPROP 2 LAST BOM_COST PROC_SIDEBAND
J 0
(-750 3500);
PAINT MONO (-750 3500);
DISPLAY INVISIBLE (-750 3500);
FORCEPROP 2 LAST ROOM CPU0
J 0
(-725 3275);
PAINT ORANGE (-725 3275);
DISPLAY INVISIBLE (-725 3275);
FORCEADD OFFPAGE..1
(-6350 4200);
FORCEPROP 2 LAST $XR0 103 
J 0
(-6602 4200);
DISPLAY 0.638298 (-6602 4200);
PAINT MONO (-6602 4200);
FORCEPROP 2 LAST PATH I169
J 0
(-6300 4275);
DISPLAY 1.021277 (-6300 4275);
PAINT ORANGE (-6300 4275);
DISPLAY INVISIBLE (-6300 4275);
FORCEPROP 2 LAST CDS_LIB mstr_standard
J 0
(-6350 4200);
PAINT MONO (-6350 4200);
DISPLAY INVISIBLE (-6350 4200);
FORCEPROP 1 LAST OFFPAGE TRUE
J 0
(-6025 4075);
DISPLAY 1.170213 (-6025 4075);
PAINT GREEN (-6025 4075);
DISPLAY INVISIBLE (-6025 4075);
FORCEPROP 1 LAST COMMENT_BODY TRUE
J 0
(-6225 4100);
DISPLAY 1.170213 (-6225 4100);
PAINT PEACH (-6225 4100);
DISPLAY INVISIBLE (-6225 4100);
FORCEADD OFFPAGE..1
(-6350 4150);
FORCEPROP 2 LAST $XR0 103 
J 0
(-6602 4150);
DISPLAY 0.638298 (-6602 4150);
PAINT MONO (-6602 4150);
FORCEPROP 2 LAST PATH I170
J 0
(-6300 4225);
DISPLAY 1.021277 (-6300 4225);
PAINT ORANGE (-6300 4225);
DISPLAY INVISIBLE (-6300 4225);
FORCEPROP 2 LAST CDS_LIB mstr_standard
J 0
(-6350 4150);
PAINT MONO (-6350 4150);
DISPLAY INVISIBLE (-6350 4150);
FORCEPROP 1 LAST OFFPAGE TRUE
J 0
(-6025 4025);
DISPLAY 1.170213 (-6025 4025);
PAINT GREEN (-6025 4025);
DISPLAY INVISIBLE (-6025 4025);
FORCEPROP 1 LAST COMMENT_BODY TRUE
J 0
(-6225 4050);
DISPLAY 1.170213 (-6225 4050);
PAINT PEACH (-6225 4050);
DISPLAY INVISIBLE (-6225 4050);
FORCEADD OFFPAGE..3
R 2
(-6375 1800);
FORCEPROP 2 LAST $XR1 112 
J 0
(-6744 1800);
DISPLAY 0.638298 (-6744 1800);
PAINT MONO (-6744 1800);
FORCEPROP 2 LAST $XR0 55 
J 0
(-6624 1800);
DISPLAY 0.638298 (-6624 1800);
PAINT MONO (-6624 1800);
FORCEPROP 2 LAST CDS_LIB mstr_standard
J 2
(-6375 1800);
PAINT MONO (-6375 1800);
DISPLAY INVISIBLE (-6375 1800);
FORCEPROP 2 LAST PATH I172
J 2
(-6425 1875);
DISPLAY 1.021277 (-6425 1875);
PAINT ORANGE (-6425 1875);
DISPLAY INVISIBLE (-6425 1875);
FORCEPROP 1 LAST OFFPAGE TRUE
J 2
(-6700 1675);
DISPLAY 0.872340 (-6700 1675);
PAINT GREEN (-6700 1675);
DISPLAY INVISIBLE (-6700 1675);
FORCEPROP 1 LAST COMMENT_BODY TRUE
J 2
(-6325 1700);
DISPLAY 0.872340 (-6325 1700);
PAINT GREEN (-6325 1700);
DISPLAY INVISIBLE (-6325 1700);
FORCEADD OFFPAGE..4
(-1400 4200);
FORCEPROP 2 LAST $XR1 55 
J 0
(-1094 4200);
DISPLAY 0.638298 (-1094 4200);
PAINT MONO (-1094 4200);
FORCEPROP 2 LAST $XR0 114 
J 0
(-1214 4200);
DISPLAY 0.638298 (-1214 4200);
PAINT MONO (-1214 4200);
FORCEPROP 2 LAST PATH I175
J 0
(-1225 4275);
DISPLAY 1.021277 (-1225 4275);
PAINT ORANGE (-1225 4275);
DISPLAY INVISIBLE (-1225 4275);
FORCEPROP 2 LAST CDS_LIB mstr_standard
J 0
(-1400 4200);
PAINT ORANGE (-1400 4200);
DISPLAY INVISIBLE (-1400 4200);
FORCEPROP 1 LAST OFFPAGE TRUE
J 0
(-1075 4075);
DISPLAY 1.170213 (-1075 4075);
PAINT GREEN (-1075 4075);
DISPLAY INVISIBLE (-1075 4075);
FORCEPROP 1 LAST COMMENT_BODY TRUE
J 0
(-1425 4100);
DISPLAY 1.170213 (-1425 4100);
PAINT PEACH (-1425 4100);
DISPLAY INVISIBLE (-1425 4100);
FORCEADD RES..2
R 2
(-6625 2875);
FORCEPROP 1 LASTPIN (-6625 2975) $PN 1
J 2
(-6630 2937);
DISPLAY 0.617021 (-6630 2937);
PAINT ORANGE (-6630 2937);
FORCEPROP 1 LASTPIN (-6625 2775) $PN 2
J 2
(-6630 2785);
DISPLAY 0.617021 (-6630 2785);
PAINT ORANGE (-6630 2785);
FORCEPROP 1 LAST PART_NUMBER G21796-365
J 2
(-6615 2750);
DISPLAY 0.617021 (-6615 2750);
PAINT BLUE (-6615 2750);
FORCEPROP 1 LAST TOLERANCE 1%
J 2
(-6670 2900);
DISPLAY 0.617021 (-6670 2900);
PAINT SKYBLUE (-6670 2900);
FORCEPROP 1 LAST WATTAGE 1/16W
J 2
(-6665 2850);
DISPLAY 0.617021 (-6665 2850);
PAINT SKYBLUE (-6665 2850);
FORCEPROP 1 LAST MATERIAL CHIP
J 2
(-6665 2800);
DISPLAY 0.617021 (-6665 2800);
PAINT SKYBLUE (-6665 2800);
FORCEPROP 1 LAST PACK_TYPE 0402
J 2
(-6665 2700);
DISPLAY 0.617021 (-6665 2700);
PAINT SKYBLUE (-6665 2700);
FORCEPROP 1 LAST LOCATION R5D1
J 2
(-6670 3000);
DISPLAY 0.617021 (-6670 3000);
PAINT AQUA (-6670 3000);
FORCEPROP 1 LAST VALUE 90.9
J 2
(-6670 2950);
DISPLAY 0.617021 (-6670 2950);
PAINT SKYBLUE (-6670 2950);
FORCEPROP 0 LAST ROOM CPU0
J 0
(-6650 3100);
DISPLAY 1.021277 (-6650 3100);
PAINT ORANGE (-6650 3100);
DISPLAY INVISIBLE (-6650 3100);
FORCEPROP 0 LAST BOM_COST PROC_SOCKET
J 0
(-6650 3100);
DISPLAY 1.021277 (-6650 3100);
PAINT ORANGE (-6650 3100);
DISPLAY INVISIBLE (-6650 3100);
FORCEPROP 2 LAST SEC_TYPE 0402
J 0
(-6675 3100);
DISPLAY 1.021277 (-6675 3100);
PAINT ORANGE (-6675 3100);
DISPLAY INVISIBLE (-6675 3100);
FORCEPROP 2 LAST SEC 1
J 0
(-6675 3100);
DISPLAY 0.680851 (-6675 3100);
PAINT MONO (-6675 3100);
DISPLAY INVISIBLE (-6675 3100);
FORCEPROP 1 LAST PATH I177
J 2
(-6675 3050);
DISPLAY 0.978723 (-6675 3050);
PAINT WHITE (-6675 3050);
DISPLAY INVISIBLE (-6675 3050);
FORCEPROP 2 LAST CDS_LIB mstr_discrete
J 0
(-6625 2875);
PAINT ORANGE (-6625 2875);
DISPLAY INVISIBLE (-6625 2875);
FORCEPROP 2 LAST CDS_LOCATION R5D1
J 2
(-6670 3000);
DISPLAY 0.617021 (-6670 3000);
PAINT AQUA (-6670 3000);
DISPLAY INVISIBLE (-6670 3000);
FORCEADD RES..2
R 2
(-6875 2925);
FORCEPROP 1 LAST LOCATION R5D2
J 2
(-6920 3050);
DISPLAY 0.617021 (-6920 3050);
PAINT AQUA (-6920 3050);
FORCEPROP 1 LASTPIN (-6875 2825) $PN 2
J 2
(-6880 2835);
DISPLAY 0.617021 (-6880 2835);
PAINT ORANGE (-6880 2835);
FORCEPROP 1 LASTPIN (-6875 3025) $PN 1
J 2
(-6880 2987);
DISPLAY 0.617021 (-6880 2987);
PAINT ORANGE (-6880 2987);
FORCEPROP 1 LAST PART_NUMBER G21796-365
J 2
(-6865 2800);
DISPLAY 0.617021 (-6865 2800);
PAINT BLUE (-6865 2800);
FORCEPROP 1 LAST TOLERANCE 1%
J 2
(-6920 2950);
DISPLAY 0.617021 (-6920 2950);
PAINT SKYBLUE (-6920 2950);
FORCEPROP 1 LAST MATERIAL CHIP
J 2
(-6915 2850);
DISPLAY 0.617021 (-6915 2850);
PAINT SKYBLUE (-6915 2850);
FORCEPROP 1 LAST VALUE 90.9
J 2
(-6920 3000);
DISPLAY 0.617021 (-6920 3000);
PAINT SKYBLUE (-6920 3000);
FORCEPROP 1 LAST WATTAGE 1/16W
J 2
(-6915 2900);
DISPLAY 0.617021 (-6915 2900);
PAINT SKYBLUE (-6915 2900);
FORCEPROP 1 LAST PACK_TYPE 0402
J 2
(-6915 2750);
DISPLAY 0.617021 (-6915 2750);
PAINT SKYBLUE (-6915 2750);
FORCEPROP 2 LAST SEC_TYPE 0402
J 0
(-6925 3150);
DISPLAY 1.021277 (-6925 3150);
PAINT ORANGE (-6925 3150);
DISPLAY INVISIBLE (-6925 3150);
FORCEPROP 0 LAST BOM_COST PROC_SOCKET
J 0
(-6900 3150);
DISPLAY 1.021277 (-6900 3150);
PAINT ORANGE (-6900 3150);
DISPLAY INVISIBLE (-6900 3150);
FORCEPROP 2 LAST SEC 1
J 0
(-6925 3150);
DISPLAY 0.680851 (-6925 3150);
PAINT MONO (-6925 3150);
DISPLAY INVISIBLE (-6925 3150);
FORCEPROP 1 LAST PATH I178
J 2
(-6925 3100);
DISPLAY 0.978723 (-6925 3100);
PAINT WHITE (-6925 3100);
DISPLAY INVISIBLE (-6925 3100);
FORCEPROP 0 LAST ROOM CPU0
J 0
(-6900 3150);
DISPLAY 1.021277 (-6900 3150);
PAINT ORANGE (-6900 3150);
DISPLAY INVISIBLE (-6900 3150);
FORCEPROP 2 LAST CDS_LOCATION R5D2
J 2
(-6920 3050);
DISPLAY 0.617021 (-6920 3050);
PAINT AQUA (-6920 3050);
DISPLAY INVISIBLE (-6920 3050);
FORCEPROP 2 LAST CDS_LIB mstr_discrete
J 0
(-6875 2925);
PAINT ORANGE (-6875 2925);
DISPLAY INVISIBLE (-6875 2925);
FORCEADD RES..2
R 2
(-7125 2925);
FORCEPROP 1 LASTPIN (-7125 3025) $PN 1
J 2
(-7130 2987);
DISPLAY 0.617021 (-7130 2987);
PAINT ORANGE (-7130 2987);
FORCEPROP 1 LASTPIN (-7125 2825) $PN 2
J 2
(-7130 2835);
DISPLAY 0.617021 (-7130 2835);
PAINT ORANGE (-7130 2835);
FORCEPROP 1 LAST MATERIAL CHIP
J 2
(-7165 2850);
DISPLAY 0.617021 (-7165 2850);
PAINT SKYBLUE (-7165 2850);
FORCEPROP 1 LAST PART_NUMBER G21796-017
J 2
(-7115 2800);
DISPLAY 0.617021 (-7115 2800);
PAINT BLUE (-7115 2800);
FORCEPROP 1 LAST PACK_TYPE 0402
J 2
(-7165 2750);
DISPLAY 0.617021 (-7165 2750);
PAINT SKYBLUE (-7165 2750);
FORCEPROP 1 LAST WATTAGE 1/16W
J 2
(-7165 2900);
DISPLAY 0.617021 (-7165 2900);
PAINT SKYBLUE (-7165 2900);
FORCEPROP 1 LAST LOCATION R6D1
J 2
(-7170 3050);
DISPLAY 0.617021 (-7170 3050);
PAINT AQUA (-7170 3050);
FORCEPROP 1 LAST TOLERANCE 1%
J 2
(-7170 2950);
DISPLAY 0.617021 (-7170 2950);
PAINT SKYBLUE (-7170 2950);
FORCEPROP 1 LAST VALUE 100.0
J 2
(-7170 3000);
DISPLAY 0.617021 (-7170 3000);
PAINT SKYBLUE (-7170 3000);
FORCEPROP 0 LAST BOM_COST PROC_SOCKET
J 0
(-7150 3150);
DISPLAY 1.021277 (-7150 3150);
PAINT ORANGE (-7150 3150);
DISPLAY INVISIBLE (-7150 3150);
FORCEPROP 0 LAST ROOM CPU0
J 0
(-7150 3150);
DISPLAY 1.021277 (-7150 3150);
PAINT ORANGE (-7150 3150);
DISPLAY INVISIBLE (-7150 3150);
FORCEPROP 2 LAST CDS_LIB mstr_discrete
J 0
(-7125 2925);
PAINT ORANGE (-7125 2925);
DISPLAY INVISIBLE (-7125 2925);
FORCEPROP 2 LAST SEC_TYPE 0402
J 0
(-7175 3150);
DISPLAY 1.021277 (-7175 3150);
PAINT ORANGE (-7175 3150);
DISPLAY INVISIBLE (-7175 3150);
FORCEPROP 2 LAST SEC 1
J 0
(-7175 3150);
DISPLAY 0.680851 (-7175 3150);
PAINT MONO (-7175 3150);
DISPLAY INVISIBLE (-7175 3150);
FORCEPROP 1 LAST PATH I179
J 2
(-7175 3100);
DISPLAY 0.978723 (-7175 3100);
PAINT WHITE (-7175 3100);
DISPLAY INVISIBLE (-7175 3100);
FORCEPROP 2 LAST CDS_LOCATION R6D1
J 2
(-7170 3050);
DISPLAY 0.617021 (-7170 3050);
PAINT AQUA (-7170 3050);
DISPLAY INVISIBLE (-7170 3050);
FORCEADD OFFPAGE..5
(-6350 3350);
FORCEPROP 2 LAST $XR0 98 
J 0
(-6574 3350);
DISPLAY 0.638298 (-6574 3350);
PAINT MONO (-6574 3350);
FORCEPROP 2 LAST PATH I18
J 0
(-6300 3425);
DISPLAY 1.361702 (-6300 3425);
PAINT ORANGE (-6300 3425);
DISPLAY INVISIBLE (-6300 3425);
FORCEPROP 2 LAST CDS_LIB mstr_standard
J 0
(-6350 3350);
PAINT MONO (-6350 3350);
DISPLAY INVISIBLE (-6350 3350);
FORCEPROP 1 LAST OFFPAGE TRUE
J 0
(-6025 3225);
DISPLAY 1.170213 (-6025 3225);
PAINT GREEN (-6025 3225);
DISPLAY INVISIBLE (-6025 3225);
FORCEPROP 1 LAST COMMENT_BODY TRUE
J 0
(-6250 3275);
DISPLAY 1.170213 (-6250 3275);
PAINT PEACH (-6250 3275);
DISPLAY INVISIBLE (-6250 3275);
FORCEADD RES..2
R 2
(-7350 2925);
FORCEPROP 1 LAST LOCATION R4P8
J 2
(-7395 3050);
DISPLAY 0.617021 (-7395 3050);
PAINT AQUA (-7395 3050);
FORCEPROP 1 LASTPIN (-7350 3025) $PN 1
J 2
(-7355 2987);
DISPLAY 0.617021 (-7355 2987);
PAINT ORANGE (-7355 2987);
FORCEPROP 1 LASTPIN (-7350 2825) $PN 2
J 2
(-7355 2835);
DISPLAY 0.617021 (-7355 2835);
PAINT ORANGE (-7355 2835);
FORCEPROP 1 LAST TOLERANCE 1%
J 2
(-7395 2950);
DISPLAY 0.617021 (-7395 2950);
PAINT SKYBLUE (-7395 2950);
FORCEPROP 1 LAST PACK_TYPE 0402
J 2
(-7390 2750);
DISPLAY 0.617021 (-7390 2750);
PAINT SKYBLUE (-7390 2750);
FORCEPROP 1 LAST VALUE 90.9
J 2
(-7395 3000);
DISPLAY 0.617021 (-7395 3000);
PAINT SKYBLUE (-7395 3000);
FORCEPROP 1 LAST WATTAGE 1/16W
J 2
(-7390 2900);
DISPLAY 0.617021 (-7390 2900);
PAINT SKYBLUE (-7390 2900);
FORCEPROP 1 LAST MATERIAL CHIP
J 2
(-7390 2850);
DISPLAY 0.617021 (-7390 2850);
PAINT SKYBLUE (-7390 2850);
FORCEPROP 1 LAST PART_NUMBER G21796-365
J 2
(-7340 2800);
DISPLAY 0.617021 (-7340 2800);
PAINT BLUE (-7340 2800);
FORCEPROP 2 LAST SEC_TYPE 0402
J 0
(-7400 3150);
DISPLAY 1.021277 (-7400 3150);
PAINT ORANGE (-7400 3150);
DISPLAY INVISIBLE (-7400 3150);
FORCEPROP 0 LAST BOM_COST PROC_SOCKET
J 0
(-7375 3150);
DISPLAY 1.021277 (-7375 3150);
PAINT ORANGE (-7375 3150);
DISPLAY INVISIBLE (-7375 3150);
FORCEPROP 2 LAST SEC 1
J 0
(-7400 3150);
DISPLAY 0.680851 (-7400 3150);
PAINT MONO (-7400 3150);
DISPLAY INVISIBLE (-7400 3150);
FORCEPROP 1 LAST PATH I180
J 2
(-7400 3100);
DISPLAY 0.978723 (-7400 3100);
PAINT WHITE (-7400 3100);
DISPLAY INVISIBLE (-7400 3100);
FORCEPROP 0 LAST ROOM CPU0
J 0
(-7375 3150);
DISPLAY 1.021277 (-7375 3150);
PAINT ORANGE (-7375 3150);
DISPLAY INVISIBLE (-7375 3150);
FORCEPROP 2 LAST CDS_LOCATION R4P8
J 2
(-7395 3050);
DISPLAY 0.617021 (-7395 3050);
PAINT AQUA (-7395 3050);
DISPLAY INVISIBLE (-7395 3050);
FORCEPROP 2 LAST CDS_LIB mstr_discrete
J 0
(-7350 2925);
PAINT ORANGE (-7350 2925);
DISPLAY INVISIBLE (-7350 2925);
FORCEADD RES..2
R 2
(-7575 3000);
FORCEPROP 1 LAST LOCATION R4P10
J 2
(-7620 3125);
DISPLAY 0.617021 (-7620 3125);
PAINT AQUA (-7620 3125);
FORCEPROP 1 LAST VALUE 90.9
J 2
(-7620 3075);
DISPLAY 0.617021 (-7620 3075);
PAINT SKYBLUE (-7620 3075);
FORCEPROP 1 LASTPIN (-7575 3100) $PN 1
J 2
(-7580 3062);
DISPLAY 0.617021 (-7580 3062);
PAINT ORANGE (-7580 3062);
FORCEPROP 1 LAST TOLERANCE 1%
J 2
(-7620 3025);
DISPLAY 0.617021 (-7620 3025);
PAINT SKYBLUE (-7620 3025);
FORCEPROP 1 LASTPIN (-7575 2900) $PN 2
J 2
(-7580 2910);
DISPLAY 0.617021 (-7580 2910);
PAINT ORANGE (-7580 2910);
FORCEPROP 1 LAST MATERIAL CHIP
J 2
(-7615 2925);
DISPLAY 0.617021 (-7615 2925);
PAINT SKYBLUE (-7615 2925);
FORCEPROP 1 LAST PACK_TYPE 0402
J 2
(-7615 2825);
DISPLAY 0.617021 (-7615 2825);
PAINT SKYBLUE (-7615 2825);
FORCEPROP 1 LAST PART_NUMBER G21796-365
J 2
(-7565 2875);
DISPLAY 0.617021 (-7565 2875);
PAINT BLUE (-7565 2875);
FORCEPROP 1 LAST WATTAGE 1/16W
J 2
(-7615 2975);
DISPLAY 0.617021 (-7615 2975);
PAINT SKYBLUE (-7615 2975);
FORCEPROP 2 LAST SEC_TYPE 0402
J 0
(-7625 3225);
DISPLAY 1.021277 (-7625 3225);
PAINT ORANGE (-7625 3225);
DISPLAY INVISIBLE (-7625 3225);
FORCEPROP 0 LAST BOM_COST PROC_SOCKET
J 0
(-7600 3225);
DISPLAY 1.021277 (-7600 3225);
PAINT ORANGE (-7600 3225);
DISPLAY INVISIBLE (-7600 3225);
FORCEPROP 0 LAST ROOM CPU0
J 0
(-7600 3225);
DISPLAY 1.021277 (-7600 3225);
PAINT ORANGE (-7600 3225);
DISPLAY INVISIBLE (-7600 3225);
FORCEPROP 1 LAST PATH I181
J 2
(-7625 3175);
DISPLAY 0.978723 (-7625 3175);
PAINT WHITE (-7625 3175);
DISPLAY INVISIBLE (-7625 3175);
FORCEPROP 2 LAST CDS_LOCATION R4P10
J 2
(-7620 3125);
DISPLAY 0.617021 (-7620 3125);
PAINT AQUA (-7620 3125);
DISPLAY INVISIBLE (-7620 3125);
FORCEPROP 2 LAST SEC 1
J 0
(-7625 3225);
DISPLAY 0.680851 (-7625 3225);
PAINT MONO (-7625 3225);
DISPLAY INVISIBLE (-7625 3225);
FORCEPROP 2 LAST CDS_LIB mstr_discrete
J 0
(-7575 3000);
PAINT ORANGE (-7575 3000);
DISPLAY INVISIBLE (-7575 3000);
FORCEADD RES..2
R 2
(-7800 3000);
FORCEPROP 1 LAST LOCATION R4P11
J 2
(-7845 3125);
DISPLAY 0.617021 (-7845 3125);
PAINT AQUA (-7845 3125);
FORCEPROP 1 LAST VALUE 100.0
J 2
(-7845 3075);
DISPLAY 0.617021 (-7845 3075);
PAINT SKYBLUE (-7845 3075);
FORCEPROP 1 LASTPIN (-7800 3100) $PN 1
J 2
(-7805 3062);
DISPLAY 0.617021 (-7805 3062);
PAINT ORANGE (-7805 3062);
FORCEPROP 1 LASTPIN (-7800 2900) $PN 2
J 2
(-7805 2910);
DISPLAY 0.617021 (-7805 2910);
PAINT ORANGE (-7805 2910);
FORCEPROP 1 LAST TOLERANCE 1%
J 2
(-7845 3025);
DISPLAY 0.617021 (-7845 3025);
PAINT SKYBLUE (-7845 3025);
FORCEPROP 1 LAST MATERIAL CHIP
J 2
(-7840 2925);
DISPLAY 0.617021 (-7840 2925);
PAINT SKYBLUE (-7840 2925);
FORCEPROP 1 LAST PART_NUMBER G21796-017
J 2
(-7790 2875);
DISPLAY 0.617021 (-7790 2875);
PAINT BLUE (-7790 2875);
FORCEPROP 1 LAST PACK_TYPE 0402
J 2
(-7840 2825);
DISPLAY 0.617021 (-7840 2825);
PAINT SKYBLUE (-7840 2825);
FORCEPROP 1 LAST WATTAGE 1/16W
J 2
(-7840 2975);
DISPLAY 0.617021 (-7840 2975);
PAINT SKYBLUE (-7840 2975);
FORCEPROP 0 LAST ROOM CPU0
J 0
(-7825 3225);
DISPLAY 1.021277 (-7825 3225);
PAINT ORANGE (-7825 3225);
DISPLAY INVISIBLE (-7825 3225);
FORCEPROP 1 LAST PATH I182
J 2
(-7850 3175);
DISPLAY 0.978723 (-7850 3175);
PAINT WHITE (-7850 3175);
DISPLAY INVISIBLE (-7850 3175);
FORCEPROP 2 LAST CDS_LOCATION R4P11
J 2
(-7845 3125);
DISPLAY 0.617021 (-7845 3125);
PAINT AQUA (-7845 3125);
DISPLAY INVISIBLE (-7845 3125);
FORCEPROP 2 LAST SEC 1
J 0
(-7850 3225);
DISPLAY 0.680851 (-7850 3225);
PAINT MONO (-7850 3225);
DISPLAY INVISIBLE (-7850 3225);
FORCEPROP 0 LAST BOM_COST PROC_SOCKET
J 0
(-7825 3225);
DISPLAY 1.021277 (-7825 3225);
PAINT ORANGE (-7825 3225);
DISPLAY INVISIBLE (-7825 3225);
FORCEPROP 2 LAST SEC_TYPE 0402
J 0
(-7850 3225);
DISPLAY 1.021277 (-7850 3225);
PAINT ORANGE (-7850 3225);
DISPLAY INVISIBLE (-7850 3225);
FORCEPROP 2 LAST CDS_LIB mstr_discrete
J 0
(-7800 3000);
PAINT ORANGE (-7800 3000);
DISPLAY INVISIBLE (-7800 3000);
FORCEADD GND..1
(-7800 2600);
FORCEPROP 3 LASTPIN (-7800 2650) SIG_NAME GND\g
J 0
(-7790 2660);
DISPLAY 0.659574 (-7790 2660);
PAINT MONO (-7790 2660);
DISPLAY INVISIBLE (-7790 2660);
FORCEPROP 2 LAST CDS_LIB mstr_symbols
J 0
(-7800 2600);
PAINT ORANGE (-7800 2600);
DISPLAY INVISIBLE (-7800 2600);
FORCEPROP 1 LAST PATH I183
J 0
(-7725 2600);
DISPLAY 0.872340 (-7725 2600);
PAINT AQUA (-7725 2600);
DISPLAY INVISIBLE (-7725 2600);
FORCEPROP 1 LAST SIZE 1B
J 0
(-7725 2550);
DISPLAY 1.170213 (-7725 2550);
PAINT GREEN (-7725 2550);
DISPLAY INVISIBLE (-7725 2550);
FORCEPROP 1 LAST VOLTAGE 0.0V
J 0
(-7845 2557);
DISPLAY 0.340426 (-7845 2557);
PAINT SKYBLUE (-7845 2557);
DISPLAY INVISIBLE (-7845 2557);
FORCEPROP 1 LAST BODY_TYPE PLUMBING
J 0
(-7845 2557);
DISPLAY 0.340426 (-7845 2557);
PAINT GREEN (-7845 2557);
DISPLAY INVISIBLE (-7845 2557);
FORCEPROP 1 LAST HDL_POWER GND
J 0
(-7800 2750);
DISPLAY 0.702128 (-7800 2750);
PAINT GREEN (-7800 2750);
DISPLAY INVISIBLE (-7800 2750);
FORCEADD RES..2
R 2
(-7350 2000);
FORCEPROP 1 LASTPIN (-7350 2100) $PN 1
J 2
(-7355 2062);
DISPLAY 0.617021 (-7355 2062);
PAINT WHITE (-7355 2062);
FORCEPROP 1 LASTPIN (-7350 1900) $PN 2
J 2
(-7355 1910);
DISPLAY 0.617021 (-7355 1910);
PAINT WHITE (-7355 1910);
FORCEPROP 1 LAST WATTAGE 1/16W
J 2
(-7390 1975);
DISPLAY 0.617021 (-7390 1975);
PAINT SKYBLUE (-7390 1975);
FORCEPROP 1 LAST MATERIAL CHIP
J 2
(-7390 1925);
DISPLAY 0.617021 (-7390 1925);
PAINT SKYBLUE (-7390 1925);
FORCEPROP 1 LAST PACK_TYPE 0402
J 2
(-7390 1825);
DISPLAY 0.617021 (-7390 1825);
PAINT SKYBLUE (-7390 1825);
FORCEPROP 1 LAST PART_NUMBER G21796-047
J 2
(-7340 1875);
DISPLAY 0.617021 (-7340 1875);
PAINT BLUE (-7340 1875);
FORCEPROP 1 LAST LOCATION R6D11
J 2
(-7395 2125);
DISPLAY 0.617021 (-7395 2125);
PAINT AQUA (-7395 2125);
FORCEPROP 1 LAST VALUE 49.9
J 2
(-7395 2075);
DISPLAY 0.617021 (-7395 2075);
PAINT SKYBLUE (-7395 2075);
FORCEPROP 1 LAST TOLERANCE 1%
J 2
(-7395 2025);
DISPLAY 0.617021 (-7395 2025);
PAINT SKYBLUE (-7395 2025);
FORCEPROP 0 LAST ROOM CPU0
J 0
(-7375 2225);
DISPLAY 1.021277 (-7375 2225);
PAINT ORANGE (-7375 2225);
DISPLAY INVISIBLE (-7375 2225);
FORCEPROP 1 LAST PATH I184
J 2
(-7400 2175);
DISPLAY 0.978723 (-7400 2175);
PAINT WHITE (-7400 2175);
DISPLAY INVISIBLE (-7400 2175);
FORCEPROP 2 LAST CDS_LOCATION R6D11
J 2
(-7395 2125);
DISPLAY 0.617021 (-7395 2125);
PAINT AQUA (-7395 2125);
DISPLAY INVISIBLE (-7395 2125);
FORCEPROP 2 LAST SEC 1
J 0
(-7400 2225);
DISPLAY 0.680851 (-7400 2225);
PAINT MONO (-7400 2225);
DISPLAY INVISIBLE (-7400 2225);
FORCEPROP 2 LAST SEC_TYPE 0402
J 0
(-7400 2225);
DISPLAY 1.021277 (-7400 2225);
PAINT ORANGE (-7400 2225);
DISPLAY INVISIBLE (-7400 2225);
FORCEPROP 0 LAST BOM_COST PROC_SOCKET
J 0
(-7375 2225);
DISPLAY 1.021277 (-7375 2225);
PAINT ORANGE (-7375 2225);
DISPLAY INVISIBLE (-7375 2225);
FORCEPROP 2 LAST CDS_LIB mstr_discrete
J 0
(-7350 2000);
PAINT ORANGE (-7350 2000);
DISPLAY INVISIBLE (-7350 2000);
FORCEADD RES..2
R 2
(-7575 2100);
FORCEPROP 1 LASTPIN (-7575 2200) $PN 1
J 2
(-7580 2162);
DISPLAY 0.617021 (-7580 2162);
PAINT WHITE (-7580 2162);
FORCEPROP 1 LAST TOLERANCE 1%
J 2
(-7620 2125);
DISPLAY 0.617021 (-7620 2125);
PAINT SKYBLUE (-7620 2125);
FORCEPROP 1 LAST LOCATION R4P3
J 2
(-7620 2225);
DISPLAY 0.617021 (-7620 2225);
PAINT AQUA (-7620 2225);
FORCEPROP 1 LAST VALUE 49.9
J 2
(-7620 2175);
DISPLAY 0.617021 (-7620 2175);
PAINT SKYBLUE (-7620 2175);
FORCEPROP 1 LAST WATTAGE 1/16W
J 2
(-7615 2075);
DISPLAY 0.617021 (-7615 2075);
PAINT SKYBLUE (-7615 2075);
FORCEPROP 1 LAST MATERIAL CHIP
J 2
(-7615 2025);
DISPLAY 0.617021 (-7615 2025);
PAINT SKYBLUE (-7615 2025);
FORCEPROP 1 LASTPIN (-7575 2000) $PN 2
J 2
(-7580 2010);
DISPLAY 0.617021 (-7580 2010);
PAINT WHITE (-7580 2010);
FORCEPROP 1 LAST PACK_TYPE 0402
J 2
(-7615 1925);
DISPLAY 0.617021 (-7615 1925);
PAINT SKYBLUE (-7615 1925);
FORCEPROP 1 LAST PART_NUMBER G21796-047
J 2
(-7565 1975);
DISPLAY 0.617021 (-7565 1975);
PAINT BLUE (-7565 1975);
FORCEPROP 2 LAST SEC 1
J 0
(-7625 2325);
DISPLAY 0.680851 (-7625 2325);
PAINT MONO (-7625 2325);
DISPLAY INVISIBLE (-7625 2325);
FORCEPROP 2 LAST SEC_TYPE 0402
J 0
(-7625 2325);
DISPLAY 1.021277 (-7625 2325);
PAINT ORANGE (-7625 2325);
DISPLAY INVISIBLE (-7625 2325);
FORCEPROP 0 LAST BOM_COST PROC_SOCKET
J 0
(-7600 2325);
DISPLAY 1.021277 (-7600 2325);
PAINT ORANGE (-7600 2325);
DISPLAY INVISIBLE (-7600 2325);
FORCEPROP 0 LAST ROOM CPU0
J 0
(-7600 2325);
DISPLAY 1.021277 (-7600 2325);
PAINT ORANGE (-7600 2325);
DISPLAY INVISIBLE (-7600 2325);
FORCEPROP 1 LAST PATH I186
J 2
(-7625 2275);
DISPLAY 0.978723 (-7625 2275);
PAINT WHITE (-7625 2275);
DISPLAY INVISIBLE (-7625 2275);
FORCEPROP 2 LAST CDS_LOCATION R4P3
J 2
(-7620 2225);
DISPLAY 0.617021 (-7620 2225);
PAINT AQUA (-7620 2225);
DISPLAY INVISIBLE (-7620 2225);
FORCEPROP 2 LAST CDS_LIB mstr_discrete
J 0
(-7575 2100);
PAINT ORANGE (-7575 2100);
DISPLAY INVISIBLE (-7575 2100);
FORCEADD GND..1
(-7800 1725);
FORCEPROP 3 LASTPIN (-7800 1775) SIG_NAME GND\g
J 0
(-7790 1785);
DISPLAY 0.659574 (-7790 1785);
PAINT MONO (-7790 1785);
DISPLAY INVISIBLE (-7790 1785);
FORCEPROP 1 LAST VOLTAGE 0.0V
J 0
(-7845 1682);
DISPLAY 0.340426 (-7845 1682);
PAINT SKYBLUE (-7845 1682);
DISPLAY INVISIBLE (-7845 1682);
FORCEPROP 1 LAST SIZE 1B
J 0
(-7725 1675);
DISPLAY 1.170213 (-7725 1675);
PAINT GREEN (-7725 1675);
DISPLAY INVISIBLE (-7725 1675);
FORCEPROP 2 LAST CDS_LIB mstr_symbols
J 0
(-7800 1725);
PAINT ORANGE (-7800 1725);
DISPLAY INVISIBLE (-7800 1725);
FORCEPROP 1 LAST PATH I187
J 0
(-7725 1725);
DISPLAY 0.872340 (-7725 1725);
PAINT AQUA (-7725 1725);
DISPLAY INVISIBLE (-7725 1725);
FORCEPROP 1 LAST BODY_TYPE PLUMBING
J 0
(-7845 1682);
DISPLAY 0.340426 (-7845 1682);
PAINT GREEN (-7845 1682);
DISPLAY INVISIBLE (-7845 1682);
FORCEPROP 1 LAST HDL_POWER GND
J 0
(-7800 1875);
DISPLAY 0.702128 (-7800 1875);
PAINT GREEN (-7800 1875);
DISPLAY INVISIBLE (-7800 1875);
FORCEADD RES..2
R 2
(-7800 2200);
FORCEPROP 1 LASTPIN (-7800 2300) $PN 1
J 2
(-7805 2262);
DISPLAY 0.617021 (-7805 2262);
PAINT WHITE (-7805 2262);
FORCEPROP 1 LASTPIN (-7800 2100) $PN 2
J 2
(-7805 2110);
DISPLAY 0.617021 (-7805 2110);
PAINT WHITE (-7805 2110);
FORCEPROP 1 LAST TOLERANCE 1%
J 2
(-7845 2225);
DISPLAY 0.617021 (-7845 2225);
PAINT SKYBLUE (-7845 2225);
FORCEPROP 1 LAST MATERIAL CHIP
J 2
(-7840 2125);
DISPLAY 0.617021 (-7840 2125);
PAINT SKYBLUE (-7840 2125);
FORCEPROP 1 LAST VALUE 49.9
J 2
(-7845 2275);
DISPLAY 0.617021 (-7845 2275);
PAINT SKYBLUE (-7845 2275);
FORCEPROP 1 LAST LOCATION R4P2
J 2
(-7845 2325);
DISPLAY 0.617021 (-7845 2325);
PAINT AQUA (-7845 2325);
FORCEPROP 1 LAST WATTAGE 1/16W
J 2
(-7840 2175);
DISPLAY 0.617021 (-7840 2175);
PAINT SKYBLUE (-7840 2175);
FORCEPROP 1 LAST PART_NUMBER G21796-047
J 2
(-7790 2075);
DISPLAY 0.617021 (-7790 2075);
PAINT BLUE (-7790 2075);
FORCEPROP 1 LAST PACK_TYPE 0402
J 2
(-7840 2025);
DISPLAY 0.617021 (-7840 2025);
PAINT SKYBLUE (-7840 2025);
FORCEPROP 2 LAST SEC 1
J 0
(-7850 2425);
DISPLAY 0.680851 (-7850 2425);
PAINT MONO (-7850 2425);
DISPLAY INVISIBLE (-7850 2425);
FORCEPROP 0 LAST BOM_COST PROC_SOCKET
J 0
(-7825 2425);
DISPLAY 1.021277 (-7825 2425);
PAINT ORANGE (-7825 2425);
DISPLAY INVISIBLE (-7825 2425);
FORCEPROP 2 LAST SEC_TYPE 0402
J 0
(-7850 2425);
DISPLAY 1.021277 (-7850 2425);
PAINT ORANGE (-7850 2425);
DISPLAY INVISIBLE (-7850 2425);
FORCEPROP 2 LAST CDS_LOCATION R4P2
J 2
(-7845 2325);
DISPLAY 0.617021 (-7845 2325);
PAINT AQUA (-7845 2325);
DISPLAY INVISIBLE (-7845 2325);
FORCEPROP 1 LAST PATH I188
J 2
(-7850 2375);
DISPLAY 0.978723 (-7850 2375);
PAINT WHITE (-7850 2375);
DISPLAY INVISIBLE (-7850 2375);
FORCEPROP 0 LAST ROOM CPU0
J 0
(-7825 2425);
DISPLAY 1.021277 (-7825 2425);
PAINT ORANGE (-7825 2425);
DISPLAY INVISIBLE (-7825 2425);
FORCEPROP 2 LAST CDS_LIB mstr_discrete
J 0
(-7800 2200);
PAINT ORANGE (-7800 2200);
DISPLAY INVISIBLE (-7800 2200);
FORCEADD RES..2
R 2
(-7125 2000);
FORCEPROP 1 LASTPIN (-7125 2100) $PN 1
J 2
(-7130 2062);
DISPLAY 0.617021 (-7130 2062);
PAINT WHITE (-7130 2062);
FORCEPROP 1 LAST VALUE 49.9
J 2
(-7170 2075);
DISPLAY 0.617021 (-7170 2075);
PAINT SKYBLUE (-7170 2075);
FORCEPROP 1 LAST TOLERANCE 1%
J 2
(-7170 2025);
DISPLAY 0.617021 (-7170 2025);
PAINT SKYBLUE (-7170 2025);
FORCEPROP 1 LASTPIN (-7125 1900) $PN 2
J 2
(-7130 1910);
DISPLAY 0.617021 (-7130 1910);
PAINT WHITE (-7130 1910);
FORCEPROP 1 LAST PACK_TYPE 0402
J 2
(-7165 1825);
DISPLAY 0.617021 (-7165 1825);
PAINT SKYBLUE (-7165 1825);
FORCEPROP 1 LAST MATERIAL CHIP
J 2
(-7165 1925);
DISPLAY 0.617021 (-7165 1925);
PAINT SKYBLUE (-7165 1925);
FORCEPROP 1 LAST PART_NUMBER G21796-047
J 2
(-7115 1875);
DISPLAY 0.617021 (-7115 1875);
PAINT BLUE (-7115 1875);
FORCEPROP 1 LAST LOCATION R4P4
J 2
(-7170 2125);
DISPLAY 0.617021 (-7170 2125);
PAINT AQUA (-7170 2125);
FORCEPROP 1 LAST WATTAGE 1/16W
J 2
(-7165 1975);
DISPLAY 0.617021 (-7165 1975);
PAINT SKYBLUE (-7165 1975);
FORCEPROP 0 LAST BOM_COST PROC_SOCKET
J 0
(-7150 2225);
DISPLAY 1.021277 (-7150 2225);
PAINT ORANGE (-7150 2225);
DISPLAY INVISIBLE (-7150 2225);
FORCEPROP 0 LAST ROOM CPU0
J 0
(-7150 2225);
DISPLAY 1.021277 (-7150 2225);
PAINT ORANGE (-7150 2225);
DISPLAY INVISIBLE (-7150 2225);
FORCEPROP 2 LAST SEC_TYPE 0402
J 0
(-7175 2225);
DISPLAY 1.021277 (-7175 2225);
PAINT ORANGE (-7175 2225);
DISPLAY INVISIBLE (-7175 2225);
FORCEPROP 2 LAST SEC 1
J 0
(-7175 2225);
DISPLAY 0.680851 (-7175 2225);
PAINT MONO (-7175 2225);
DISPLAY INVISIBLE (-7175 2225);
FORCEPROP 2 LAST CDS_LOCATION R4P4
J 2
(-7170 2125);
DISPLAY 0.617021 (-7170 2125);
PAINT AQUA (-7170 2125);
DISPLAY INVISIBLE (-7170 2125);
FORCEPROP 1 LAST PATH I189
J 2
(-7175 2175);
DISPLAY 0.978723 (-7175 2175);
PAINT WHITE (-7175 2175);
DISPLAY INVISIBLE (-7175 2175);
FORCEPROP 2 LAST CDS_LIB mstr_discrete
J 0
(-7125 2000);
PAINT ORANGE (-7125 2000);
DISPLAY INVISIBLE (-7125 2000);
FORCEADD OFFPAGE..4
(-1400 4250);
FORCEPROP 2 LAST $XR1 55 
J 0
(-1094 4250);
DISPLAY 0.638298 (-1094 4250);
PAINT MONO (-1094 4250);
FORCEPROP 2 LAST $XR0 118 
J 0
(-1214 4250);
DISPLAY 0.638298 (-1214 4250);
PAINT MONO (-1214 4250);
FORCEPROP 2 LAST PATH I196
J 0
(-1225 4325);
DISPLAY 1.021277 (-1225 4325);
PAINT ORANGE (-1225 4325);
DISPLAY INVISIBLE (-1225 4325);
FORCEPROP 2 LAST CDS_LIB mstr_standard
J 0
(-1400 4250);
PAINT ORANGE (-1400 4250);
DISPLAY INVISIBLE (-1400 4250);
FORCEPROP 1 LAST OFFPAGE TRUE
J 0
(-1075 4125);
DISPLAY 1.170213 (-1075 4125);
PAINT GREEN (-1075 4125);
DISPLAY INVISIBLE (-1075 4125);
FORCEPROP 1 LAST COMMENT_BODY TRUE
J 0
(-1425 4150);
DISPLAY 1.170213 (-1425 4150);
PAINT PEACH (-1425 4150);
DISPLAY INVISIBLE (-1425 4150);
FORCEADD OFFPAGE..2
(-1400 4350);
FORCEPROP 2 LAST $XR0 90 
J 0
(-1211 4350);
DISPLAY 0.638298 (-1211 4350);
PAINT MONO (-1211 4350);
FORCEPROP 2 LAST PATH I197
J 0
(-1225 4425);
DISPLAY 1.021277 (-1225 4425);
PAINT ORANGE (-1225 4425);
DISPLAY INVISIBLE (-1225 4425);
FORCEPROP 2 LAST CDS_LIB mstr_standard
J 0
(-1400 4350);
PAINT ORANGE (-1400 4350);
DISPLAY INVISIBLE (-1400 4350);
FORCEPROP 1 LAST OFFPAGE TRUE
J 0
(-1075 4225);
DISPLAY 0.872340 (-1075 4225);
PAINT GREEN (-1075 4225);
DISPLAY INVISIBLE (-1075 4225);
FORCEPROP 1 LAST COMMENT_BODY TRUE
J 0
(-1445 4255);
DISPLAY 0.872340 (-1445 4255);
PAINT GREEN (-1445 4255);
DISPLAY INVISIBLE (-1445 4255);
FORCEADD OFFPAGE..1
(-6350 4500);
FORCEPROP 2 LAST $XR0 103 
J 0
(-6602 4500);
DISPLAY 0.638298 (-6602 4500);
PAINT MONO (-6602 4500);
FORCEPROP 2 LAST CDS_LIB mstr_standard
J 0
(-6350 4500);
PAINT MONO (-6350 4500);
DISPLAY INVISIBLE (-6350 4500);
FORCEPROP 2 LAST PATH I2
J 0
(-6650 4550);
DISPLAY 1.361702 (-6650 4550);
PAINT ORANGE (-6650 4550);
DISPLAY INVISIBLE (-6650 4550);
FORCEPROP 1 LAST OFFPAGE TRUE
J 0
(-6025 4375);
DISPLAY 1.170213 (-6025 4375);
PAINT GREEN (-6025 4375);
DISPLAY INVISIBLE (-6025 4375);
FORCEPROP 1 LAST COMMENT_BODY TRUE
J 0
(-6225 4400);
DISPLAY 1.170213 (-6225 4400);
PAINT PEACH (-6225 4400);
DISPLAY INVISIBLE (-6225 4400);
FORCEADD OFFPAGE..2
(-550 1250);
FORCEPROP 2 LAST $XR2 190 
J 0
(-361 1214);
DISPLAY 0.638298 (-361 1214);
PAINT MONO (-361 1214);
FORCEPROP 2 LAST $XR1 144 
J 0
(-241 1250);
DISPLAY 0.638298 (-241 1250);
PAINT MONO (-241 1250);
FORCEPROP 2 LAST $XR0 118 
J 0
(-361 1250);
DISPLAY 0.638298 (-361 1250);
PAINT MONO (-361 1250);
FORCEPROP 2 LAST PATH I200
J 0
(-375 1325);
DISPLAY 1.021277 (-375 1325);
PAINT ORANGE (-375 1325);
DISPLAY INVISIBLE (-375 1325);
FORCEPROP 2 LAST CDS_LIB mstr_standard
J 0
(-550 1250);
PAINT ORANGE (-550 1250);
DISPLAY INVISIBLE (-550 1250);
FORCEPROP 1 LAST OFFPAGE TRUE
J 0
(-225 1125);
DISPLAY 1.170213 (-225 1125);
PAINT GREEN (-225 1125);
DISPLAY INVISIBLE (-225 1125);
FORCEPROP 1 LAST COMMENT_BODY TRUE
J 0
(-595 1155);
DISPLAY 1.170213 (-595 1155);
PAINT PEACH (-595 1155);
DISPLAY INVISIBLE (-595 1155);
FORCEADD OFFPAGE..2
(-2075 2600);
FORCEPROP 2 LAST $XR0 90 
J 0
(-1886 2600);
DISPLAY 0.638298 (-1886 2600);
PAINT MONO (-1886 2600);
FORCEPROP 2 LAST PATH I201
J 0
(-1900 2675);
DISPLAY 1.021277 (-1900 2675);
PAINT ORANGE (-1900 2675);
DISPLAY INVISIBLE (-1900 2675);
FORCEPROP 2 LAST CDS_LIB mstr_standard
J 0
(-2075 2600);
PAINT ORANGE (-2075 2600);
DISPLAY INVISIBLE (-2075 2600);
FORCEPROP 1 LAST OFFPAGE TRUE
J 0
(-1750 2475);
DISPLAY 0.872340 (-1750 2475);
PAINT GREEN (-1750 2475);
DISPLAY INVISIBLE (-1750 2475);
FORCEPROP 1 LAST COMMENT_BODY TRUE
J 0
(-2120 2505);
DISPLAY 0.872340 (-2120 2505);
PAINT GREEN (-2120 2505);
DISPLAY INVISIBLE (-2120 2505);
FORCEADD OFFPAGE..2
(-2075 2650);
FORCEPROP 2 LAST $XR0 90 
J 0
(-1886 2650);
DISPLAY 0.638298 (-1886 2650);
PAINT MONO (-1886 2650);
FORCEPROP 2 LAST PATH I202
J 0
(-1900 2725);
DISPLAY 1.021277 (-1900 2725);
PAINT ORANGE (-1900 2725);
DISPLAY INVISIBLE (-1900 2725);
FORCEPROP 2 LAST CDS_LIB mstr_standard
J 0
(-2075 2650);
PAINT ORANGE (-2075 2650);
DISPLAY INVISIBLE (-2075 2650);
FORCEPROP 1 LAST OFFPAGE TRUE
J 0
(-1750 2525);
DISPLAY 0.872340 (-1750 2525);
PAINT GREEN (-1750 2525);
DISPLAY INVISIBLE (-1750 2525);
FORCEPROP 1 LAST COMMENT_BODY TRUE
J 0
(-2120 2555);
DISPLAY 0.872340 (-2120 2555);
PAINT GREEN (-2120 2555);
DISPLAY INVISIBLE (-2120 2555);
FORCEADD RES..2
R 2
(-6900 2000);
FORCEPROP 1 LASTPIN (-6900 2100) $PN 1
J 2
(-6905 2062);
DISPLAY 0.617021 (-6905 2062);
PAINT WHITE (-6905 2062);
FORCEPROP 1 LAST VALUE 49.9
J 2
(-6945 2075);
DISPLAY 0.617021 (-6945 2075);
PAINT SKYBLUE (-6945 2075);
FORCEPROP 1 LAST LOCATION R6D2
J 2
(-6945 2125);
DISPLAY 0.617021 (-6945 2125);
PAINT AQUA (-6945 2125);
FORCEPROP 1 LAST TOLERANCE 1%
J 2
(-6945 2025);
DISPLAY 0.617021 (-6945 2025);
PAINT SKYBLUE (-6945 2025);
FORCEPROP 1 LASTPIN (-6900 1900) $PN 2
J 2
(-6905 1910);
DISPLAY 0.617021 (-6905 1910);
PAINT WHITE (-6905 1910);
FORCEPROP 1 LAST WATTAGE 1/16W
J 2
(-6940 1975);
DISPLAY 0.617021 (-6940 1975);
PAINT SKYBLUE (-6940 1975);
FORCEPROP 1 LAST PACK_TYPE 0402
J 2
(-6940 1825);
DISPLAY 0.617021 (-6940 1825);
PAINT SKYBLUE (-6940 1825);
FORCEPROP 1 LAST PART_NUMBER G21796-047
J 2
(-6890 1875);
DISPLAY 0.617021 (-6890 1875);
PAINT BLUE (-6890 1875);
FORCEPROP 1 LAST MATERIAL CHIP
J 2
(-6940 1925);
DISPLAY 0.617021 (-6940 1925);
PAINT SKYBLUE (-6940 1925);
FORCEPROP 0 LAST BOM_COST PROC_SOCKET
J 0
(-6925 2225);
DISPLAY 1.021277 (-6925 2225);
PAINT ORANGE (-6925 2225);
DISPLAY INVISIBLE (-6925 2225);
FORCEPROP 0 LAST ROOM CPU0
J 0
(-6925 2225);
DISPLAY 1.021277 (-6925 2225);
PAINT ORANGE (-6925 2225);
DISPLAY INVISIBLE (-6925 2225);
FORCEPROP 1 LAST PATH I204
J 2
(-6950 2175);
DISPLAY 0.978723 (-6950 2175);
PAINT WHITE (-6950 2175);
DISPLAY INVISIBLE (-6950 2175);
FORCEPROP 2 LAST CDS_LOCATION R6D2
J 2
(-6945 2125);
DISPLAY 0.617021 (-6945 2125);
PAINT AQUA (-6945 2125);
DISPLAY INVISIBLE (-6945 2125);
FORCEPROP 2 LAST SEC 1
J 0
(-6950 2225);
DISPLAY 0.680851 (-6950 2225);
PAINT MONO (-6950 2225);
DISPLAY INVISIBLE (-6950 2225);
FORCEPROP 2 LAST SEC_TYPE 0402
J 0
(-6950 2225);
DISPLAY 1.021277 (-6950 2225);
PAINT ORANGE (-6950 2225);
DISPLAY INVISIBLE (-6950 2225);
FORCEPROP 2 LAST CDS_LIB mstr_discrete
J 0
(-6900 2000);
PAINT ORANGE (-6900 2000);
DISPLAY INVISIBLE (-6900 2000);
FORCEADD OFFPAGE..4
(-1800 2100);
FORCEPROP 2 LAST $XR0 97 
J 0
(-1614 2100);
DISPLAY 0.638298 (-1614 2100);
PAINT MONO (-1614 2100);
FORCEPROP 2 LAST PATH I205
J 0
(-1625 2175);
DISPLAY 1.021277 (-1625 2175);
PAINT ORANGE (-1625 2175);
DISPLAY INVISIBLE (-1625 2175);
FORCEPROP 2 LAST CDS_LIB mstr_standard
J 0
(-1800 2100);
PAINT ORANGE (-1800 2100);
DISPLAY INVISIBLE (-1800 2100);
FORCEPROP 1 LAST OFFPAGE TRUE
J 0
(-1475 1975);
DISPLAY 1.170213 (-1475 1975);
PAINT GREEN (-1475 1975);
DISPLAY INVISIBLE (-1475 1975);
FORCEPROP 1 LAST COMMENT_BODY TRUE
J 0
(-1825 2000);
DISPLAY 1.170213 (-1825 2000);
PAINT PEACH (-1825 2000);
DISPLAY INVISIBLE (-1825 2000);
FORCEADD OFFPAGE..4
(-1800 1900);
FORCEPROP 2 LAST $XR0 90 
J 0
(-1614 1900);
DISPLAY 0.638298 (-1614 1900);
PAINT MONO (-1614 1900);
FORCEPROP 2 LAST PATH I209
J 0
(-1625 1975);
DISPLAY 1.021277 (-1625 1975);
PAINT ORANGE (-1625 1975);
DISPLAY INVISIBLE (-1625 1975);
FORCEPROP 2 LAST CDS_LIB mstr_standard
J 0
(-1800 1900);
PAINT ORANGE (-1800 1900);
DISPLAY INVISIBLE (-1800 1900);
FORCEPROP 1 LAST OFFPAGE TRUE
J 0
(-1475 1775);
DISPLAY 1.170213 (-1475 1775);
PAINT GREEN (-1475 1775);
DISPLAY INVISIBLE (-1475 1775);
FORCEPROP 1 LAST COMMENT_BODY TRUE
J 0
(-1825 1800);
DISPLAY 1.170213 (-1825 1800);
PAINT PEACH (-1825 1800);
DISPLAY INVISIBLE (-1825 1800);
FORCEADD OFFPAGE..5
(-6350 3600);
FORCEPROP 2 LAST $XR0 98 
J 0
(-6574 3600);
DISPLAY 0.638298 (-6574 3600);
PAINT MONO (-6574 3600);
FORCEPROP 2 LAST PATH I212
J 0
(-6300 3675);
DISPLAY 1.021277 (-6300 3675);
PAINT ORANGE (-6300 3675);
DISPLAY INVISIBLE (-6300 3675);
FORCEPROP 2 LAST CDS_LIB mstr_standard
J 0
(-6350 3600);
PAINT ORANGE (-6350 3600);
DISPLAY INVISIBLE (-6350 3600);
FORCEPROP 1 LAST OFFPAGE TRUE
J 0
(-6025 3475);
DISPLAY 1.170213 (-6025 3475);
PAINT GREEN (-6025 3475);
DISPLAY INVISIBLE (-6025 3475);
FORCEPROP 1 LAST COMMENT_BODY TRUE
J 0
(-6250 3525);
DISPLAY 1.170213 (-6250 3525);
PAINT PEACH (-6250 3525);
DISPLAY INVISIBLE (-6250 3525);
FORCEADD OFFPAGE..5
(-6350 3550);
FORCEPROP 2 LAST $XR0 98 
J 0
(-6574 3550);
DISPLAY 0.638298 (-6574 3550);
PAINT MONO (-6574 3550);
FORCEPROP 2 LAST PATH I213
J 0
(-6300 3625);
DISPLAY 1.021277 (-6300 3625);
PAINT ORANGE (-6300 3625);
DISPLAY INVISIBLE (-6300 3625);
FORCEPROP 2 LAST CDS_LIB mstr_standard
J 0
(-6350 3550);
PAINT ORANGE (-6350 3550);
DISPLAY INVISIBLE (-6350 3550);
FORCEPROP 1 LAST OFFPAGE TRUE
J 0
(-6025 3425);
DISPLAY 1.170213 (-6025 3425);
PAINT GREEN (-6025 3425);
DISPLAY INVISIBLE (-6025 3425);
FORCEPROP 1 LAST COMMENT_BODY TRUE
J 0
(-6250 3475);
DISPLAY 1.170213 (-6250 3475);
PAINT PEACH (-6250 3475);
DISPLAY INVISIBLE (-6250 3475);
FORCEADD OFFPAGE..5
(-6350 3400);
FORCEPROP 2 LAST $XR0 98 
J 0
(-6574 3400);
DISPLAY 0.638298 (-6574 3400);
PAINT MONO (-6574 3400);
FORCEPROP 2 LAST PATH I214
J 0
(-6300 3475);
DISPLAY 1.021277 (-6300 3475);
PAINT ORANGE (-6300 3475);
DISPLAY INVISIBLE (-6300 3475);
FORCEPROP 2 LAST CDS_LIB mstr_standard
J 0
(-6350 3400);
PAINT ORANGE (-6350 3400);
DISPLAY INVISIBLE (-6350 3400);
FORCEPROP 1 LAST OFFPAGE TRUE
J 0
(-6025 3275);
DISPLAY 1.170213 (-6025 3275);
PAINT GREEN (-6025 3275);
DISPLAY INVISIBLE (-6025 3275);
FORCEPROP 1 LAST COMMENT_BODY TRUE
J 0
(-6250 3325);
DISPLAY 1.170213 (-6250 3325);
PAINT PEACH (-6250 3325);
DISPLAY INVISIBLE (-6250 3325);
FORCEADD OFFPAGE..5
(-6350 3450);
FORCEPROP 2 LAST $XR0 98 
J 0
(-6574 3450);
DISPLAY 0.638298 (-6574 3450);
PAINT MONO (-6574 3450);
FORCEPROP 2 LAST PATH I215
J 0
(-6300 3525);
DISPLAY 1.021277 (-6300 3525);
PAINT ORANGE (-6300 3525);
DISPLAY INVISIBLE (-6300 3525);
FORCEPROP 2 LAST CDS_LIB mstr_standard
J 0
(-6350 3450);
PAINT ORANGE (-6350 3450);
DISPLAY INVISIBLE (-6350 3450);
FORCEPROP 1 LAST OFFPAGE TRUE
J 0
(-6025 3325);
DISPLAY 1.170213 (-6025 3325);
PAINT GREEN (-6025 3325);
DISPLAY INVISIBLE (-6025 3325);
FORCEPROP 1 LAST COMMENT_BODY TRUE
J 0
(-6250 3375);
DISPLAY 1.170213 (-6250 3375);
PAINT PEACH (-6250 3375);
DISPLAY INVISIBLE (-6250 3375);
FORCEADD SOCKET_P_MECH_A..1
(-7525 4450);
FORCEPROP 1 LAST PACK_TYPE RIGHT
J 0
(-7420 4425);
DISPLAY 0.617021 (-7420 4425);
PAINT SKYBLUE (-7420 4425);
FORCEPROP 1 LAST MATERIAL PLASTIC
J 0
(-7875 4575);
DISPLAY 0.617021 (-7875 4575);
PAINT SKYBLUE (-7875 4575);
FORCEPROP 1 LAST PART_NUMBER H37604-101
J 0
(-7875 4350);
DISPLAY 0.617021 (-7875 4350);
PAINT BLUE (-7875 4350);
FORCEPROP 1 LAST LOCATION XRU1
J 0
(-7875 4525);
DISPLAY 0.617021 (-7875 4525);
PAINT AQUA (-7875 4525);
FORCEPROP 1 LAST SKT_NUMBER P0
J 0
(-7850 4425);
DISPLAY 0.808511 (-7850 4425);
PAINT GREEN (-7850 4425);
FORCEPROP 2 LAST CDS_LIB chpset_lib
J 0
(-7525 4450);
PAINT ORANGE (-7525 4450);
DISPLAY INVISIBLE (-7525 4450);
FORCEPROP 1 LAST PATH I216
J 0
(-7525 4570);
DISPLAY 0.872340 (-7525 4570);
PAINT WHITE (-7525 4570);
DISPLAY INVISIBLE (-7525 4570);
FORCEPROP 0 LAST ROOM CPU0
J 0
(-7875 4675);
DISPLAY 1.021277 (-7875 4675);
PAINT ORANGE (-7875 4675);
DISPLAY INVISIBLE (-7875 4675);
FORCEPROP 0 LAST BOM_COST PROC_SOCKET
J 0
(-7875 4775);
DISPLAY 1.021277 (-7875 4775);
PAINT ORANGE (-7875 4775);
DISPLAY INVISIBLE (-7875 4775);
FORCEPROP 2 LAST CDS_LOCATION XRU1
J 0
(-7875 4525);
DISPLAY 0.617021 (-7875 4525);
PAINT AQUA (-7875 4525);
DISPLAY INVISIBLE (-7875 4525);
FORCEADD SOCKET_P_MECH_A..1
(-7525 4150);
FORCEPROP 1 LAST PACK_TYPE LEFT
J 0
(-7420 4125);
DISPLAY 0.617021 (-7420 4125);
PAINT SKYBLUE (-7420 4125);
FORCEPROP 1 LAST SKT_NUMBER P0
J 0
(-7850 4125);
DISPLAY 0.808511 (-7850 4125);
PAINT GREEN (-7850 4125);
FORCEPROP 1 LAST PART_NUMBER H37604-201
J 0
(-7875 4050);
DISPLAY 0.617021 (-7875 4050);
PAINT BLUE (-7875 4050);
FORCEPROP 1 LAST LOCATION XLU1
J 0
(-7875 4225);
DISPLAY 0.617021 (-7875 4225);
PAINT AQUA (-7875 4225);
FORCEPROP 1 LAST MATERIAL PLASTIC
J 0
(-7875 4275);
DISPLAY 0.617021 (-7875 4275);
PAINT SKYBLUE (-7875 4275);
FORCEPROP 2 LAST CDS_LIB chpset_lib
J 0
(-7525 4150);
PAINT ORANGE (-7525 4150);
DISPLAY INVISIBLE (-7525 4150);
FORCEPROP 1 LAST PATH I217
J 0
(-7525 4270);
DISPLAY 0.872340 (-7525 4270);
PAINT WHITE (-7525 4270);
DISPLAY INVISIBLE (-7525 4270);
FORCEPROP 0 LAST ROOM CPU0
J 0
(-7875 4375);
DISPLAY 1.021277 (-7875 4375);
PAINT ORANGE (-7875 4375);
DISPLAY INVISIBLE (-7875 4375);
FORCEPROP 2 LAST CDS_LOCATION XLU1
J 0
(-7875 4225);
DISPLAY 0.617021 (-7875 4225);
PAINT AQUA (-7875 4225);
DISPLAY INVISIBLE (-7875 4225);
FORCEPROP 0 LAST BOM_COST PROC_SOCKET
J 0
(-7875 4475);
DISPLAY 1.021277 (-7875 4475);
PAINT ORANGE (-7875 4475);
DISPLAY INVISIBLE (-7875 4475);
FORCEADD RES..1
(-2075 4200);
FORCEPROP 1 LAST WATTAGE 1/16W
J 2
(-2025 4150);
DISPLAY 0.617021 (-2025 4150);
PAINT SKYBLUE (-2025 4150);
FORCEPROP 1 LASTPIN (-2175 4200) $PN 1
J 0
(-2163 4212);
DISPLAY 0.617021 (-2163 4212);
PAINT ORANGE (-2163 4212);
FORCEPROP 1 LAST TOLERANCE 1%
J 0
(-2225 4150);
DISPLAY 0.617021 (-2225 4150);
PAINT SKYBLUE (-2225 4150);
FORCEPROP 1 LAST LOCATION R4P19
J 0
(-2475 4150);
DISPLAY 0.617021 (-2475 4150);
PAINT AQUA (-2475 4150);
FORCEPROP 1 LAST PART_NUMBER G21796-047
J 0
(-1750 4150);
DISPLAY 0.617021 (-1750 4150);
PAINT BLUE (-1750 4150);
FORCEPROP 1 LAST VALUE 49.9
J 2
(-2250 4150);
DISPLAY 0.617021 (-2250 4150);
PAINT SKYBLUE (-2250 4150);
FORCEPROP 1 LASTPIN (-1975 4200) $PN 2
J 0
(-2013 4212);
DISPLAY 0.617021 (-2013 4212);
PAINT ORANGE (-2013 4212);
FORCEPROP 1 LAST MATERIAL CHIP
J 0
(-2000 4150);
DISPLAY 0.617021 (-2000 4150);
PAINT SKYBLUE (-2000 4150);
FORCEPROP 1 LAST PACK_TYPE 0402
J 0
(-1875 4150);
DISPLAY 0.617021 (-1875 4150);
PAINT SKYBLUE (-1875 4150);
FORCEPROP 0 LAST ROOM CPU0
J 0
(-2125 4400);
DISPLAY 1.021277 (-2125 4400);
PAINT ORANGE (-2125 4400);
DISPLAY INVISIBLE (-2125 4400);
FORCEPROP 2 LAST SEC 1
J 0
(-2125 4400);
DISPLAY 0.680851 (-2125 4400);
PAINT MONO (-2125 4400);
DISPLAY INVISIBLE (-2125 4400);
FORCEPROP 0 LAST BOM_COST PROC_SOCKET
J 0
(-2075 4400);
DISPLAY 1.021277 (-2075 4400);
PAINT ORANGE (-2075 4400);
DISPLAY INVISIBLE (-2075 4400);
FORCEPROP 2 LAST SEC_TYPE 0402
J 0
(-2125 4400);
DISPLAY 1.021277 (-2125 4400);
PAINT ORANGE (-2125 4400);
DISPLAY INVISIBLE (-2125 4400);
FORCEPROP 1 LAST PATH I219
J 0
(-2125 4350);
DISPLAY 0.978723 (-2125 4350);
PAINT WHITE (-2125 4350);
DISPLAY INVISIBLE (-2125 4350);
FORCEPROP 2 LAST CDS_LOCATION R4P19
J 0
(-2075 4300);
DISPLAY 0.617021 (-2075 4300);
PAINT AQUA (-2075 4300);
DISPLAY INVISIBLE (-2075 4300);
FORCEPROP 2 LAST CDS_LIB mstr_discrete
J 0
(-2075 4200);
PAINT ORANGE (-2075 4200);
DISPLAY INVISIBLE (-2075 4200);
FORCEADD RES..2
(-1700 2700);
FORCEPROP 1 LAST PACK_TYPE 0402
J 0
(-1610 2575);
DISPLAY 0.617021 (-1610 2575);
PAINT SKYBLUE (-1610 2575);
FORCEPROP 1 LAST LOCATION R5N2
J 2
(-1525 2825);
DISPLAY 0.617021 (-1525 2825);
PAINT AQUA (-1525 2825);
FORCEPROP 1 LAST MATERIAL CHIP
J 0
(-1610 2625);
DISPLAY 0.617021 (-1610 2625);
PAINT SKYBLUE (-1610 2625);
FORCEPROP 1 LAST WATTAGE 1/16W
J 0
(-1610 2675);
DISPLAY 0.617021 (-1610 2675);
PAINT SKYBLUE (-1610 2675);
FORCEPROP 1 LASTPIN (-1700 2800) $PN 1
J 0
(-1695 2762);
DISPLAY 0.617021 (-1695 2762);
PAINT ORANGE (-1695 2762);
FORCEPROP 1 LASTPIN (-1700 2600) $PN 2
J 0
(-1695 2610);
DISPLAY 0.617021 (-1695 2610);
PAINT ORANGE (-1695 2610);
FORCEPROP 1 LAST TOLERANCE 1%
J 0
(-1605 2725);
DISPLAY 0.617021 (-1605 2725);
PAINT SKYBLUE (-1605 2725);
FORCEPROP 1 LAST PART_NUMBER G21796-336
R 1
J 0
(-1635 2575);
DISPLAY 0.617021 (-1635 2575);
PAINT BLUE (-1635 2575);
FORCEPROP 1 LAST VALUE 1.8K
J 0
(-1605 2775);
DISPLAY 0.617021 (-1605 2775);
PAINT SKYBLUE (-1605 2775);
FORCEPROP 1 LAST PATH I227
J 0
(-1650 2875);
DISPLAY 0.978723 (-1650 2875);
PAINT WHITE (-1650 2875);
DISPLAY INVISIBLE (-1650 2875);
FORCEPROP 2 LAST CDS_LOCATION R5N2
J 2
(-1550 2825);
DISPLAY 0.617021 (-1550 2825);
PAINT AQUA (-1550 2825);
DISPLAY INVISIBLE (-1550 2825);
FORCEPROP 2 LAST SEC 1
J 0
(-1650 2925);
DISPLAY 0.680851 (-1650 2925);
PAINT MONO (-1650 2925);
DISPLAY INVISIBLE (-1650 2925);
FORCEPROP 2 LAST SEC_TYPE 0402
J 0
(-1650 2925);
DISPLAY 1.021277 (-1650 2925);
PAINT ORANGE (-1650 2925);
DISPLAY INVISIBLE (-1650 2925);
FORCEPROP 2 LAST BOM_COST PROC_SIDEBAND
J 0
(-1700 2700);
PAINT WHITE (-1700 2700);
DISPLAY INVISIBLE (-1700 2700);
FORCEPROP 2 LAST CDS_LIB mstr_discrete
J 2
(-1700 2700);
PAINT ORANGE (-1700 2700);
DISPLAY INVISIBLE (-1700 2700);
FORCEPROP 2 LAST ROOM CPU0
J 0
(-1675 2475);
PAINT WHITE (-1675 2475);
DISPLAY INVISIBLE (-1675 2475);
FORCEADD P3V3_STBY..1
(-700 3000);
FORCEPROP 3 LASTPIN (-700 2950) SIG_NAME P3V3_STBY\g
J 0
(-690 2960);
DISPLAY 0.659574 (-690 2960);
PAINT MONO (-690 2960);
DISPLAY INVISIBLE (-690 2960);
FORCEPROP 1 LAST VOLTAGE 3.3V
J 0
(-745 2957);
DISPLAY 0.340426 (-745 2957);
PAINT SKYBLUE (-745 2957);
DISPLAY INVISIBLE (-745 2957);
FORCEPROP 2 LAST CDS_LIB mstr_symbols
J 0
(-700 3000);
PAINT ORANGE (-700 3000);
DISPLAY INVISIBLE (-700 3000);
FORCEPROP 1 LAST SIZE 1B
J 0
(-655 3022);
DISPLAY 0.340426 (-655 3022);
PAINT GREEN (-655 3022);
DISPLAY INVISIBLE (-655 3022);
FORCEPROP 1 LAST PATH I228
J 0
(-655 3002);
DISPLAY 0.340426 (-655 3002);
PAINT GREEN (-655 3002);
DISPLAY INVISIBLE (-655 3002);
FORCEPROP 1 LAST BODY_TYPE PLUMBING
J 0
(-745 2957);
DISPLAY 0.340426 (-745 2957);
PAINT GREEN (-745 2957);
DISPLAY INVISIBLE (-745 2957);
FORCEPROP 1 LAST HDL_POWER P3V3_STBY
J 0
(-1000 2875);
DISPLAY 0.872340 (-1000 2875);
PAINT GREEN (-1000 2875);
DISPLAY INVISIBLE (-1000 2875);
FORCEADD OFFPAGE..2
(-550 2450);
FORCEPROP 2 LAST $XR0 190 
J 0
(-361 2450);
DISPLAY 0.638298 (-361 2450);
PAINT MONO (-361 2450);
FORCEPROP 2 LAST PATH I233
J 0
(-375 2525);
DISPLAY 1.021277 (-375 2525);
PAINT ORANGE (-375 2525);
DISPLAY INVISIBLE (-375 2525);
FORCEPROP 2 LAST CDS_LIB mstr_standard
J 0
(-550 2450);
PAINT ORANGE (-550 2450);
DISPLAY INVISIBLE (-550 2450);
FORCEPROP 1 LAST OFFPAGE TRUE
J 0
(-225 2325);
DISPLAY 1.170213 (-225 2325);
PAINT GREEN (-225 2325);
DISPLAY INVISIBLE (-225 2325);
FORCEPROP 1 LAST COMMENT_BODY TRUE
J 0
(-595 2355);
DISPLAY 1.170213 (-595 2355);
PAINT PEACH (-595 2355);
DISPLAY INVISIBLE (-595 2355);
FORCEADD OFFPAGE..2
(-550 2400);
FORCEPROP 2 LAST $XR0 190 
J 0
(-361 2400);
DISPLAY 0.638298 (-361 2400);
PAINT MONO (-361 2400);
FORCEPROP 2 LAST PATH I234
J 0
(-375 2475);
DISPLAY 1.021277 (-375 2475);
PAINT ORANGE (-375 2475);
DISPLAY INVISIBLE (-375 2475);
FORCEPROP 2 LAST CDS_LIB mstr_standard
J 0
(-550 2400);
PAINT ORANGE (-550 2400);
DISPLAY INVISIBLE (-550 2400);
FORCEPROP 1 LAST OFFPAGE TRUE
J 0
(-225 2275);
DISPLAY 1.170213 (-225 2275);
PAINT GREEN (-225 2275);
DISPLAY INVISIBLE (-225 2275);
FORCEPROP 1 LAST COMMENT_BODY TRUE
J 0
(-595 2305);
DISPLAY 1.170213 (-595 2305);
PAINT PEACH (-595 2305);
DISPLAY INVISIBLE (-595 2305);
FORCEADD OFFPAGE..2
(-550 2300);
FORCEPROP 2 LAST $XR0 190 
J 0
(-361 2300);
DISPLAY 0.638298 (-361 2300);
PAINT MONO (-361 2300);
FORCEPROP 2 LAST PATH I235
J 0
(-375 2375);
DISPLAY 1.021277 (-375 2375);
PAINT ORANGE (-375 2375);
DISPLAY INVISIBLE (-375 2375);
FORCEPROP 2 LAST CDS_LIB mstr_standard
J 0
(-550 2300);
PAINT ORANGE (-550 2300);
DISPLAY INVISIBLE (-550 2300);
FORCEPROP 1 LAST OFFPAGE TRUE
J 0
(-225 2175);
DISPLAY 1.170213 (-225 2175);
PAINT GREEN (-225 2175);
DISPLAY INVISIBLE (-225 2175);
FORCEPROP 1 LAST COMMENT_BODY TRUE
J 0
(-595 2205);
DISPLAY 1.170213 (-595 2205);
PAINT PEACH (-595 2205);
DISPLAY INVISIBLE (-595 2205);
FORCEADD OFFPAGE..2
(-550 2250);
FORCEPROP 2 LAST $XR1 190 
J 0
(-241 2250);
DISPLAY 0.638298 (-241 2250);
PAINT MONO (-241 2250);
FORCEPROP 2 LAST $XR0 113 
J 0
(-361 2250);
DISPLAY 0.638298 (-361 2250);
PAINT MONO (-361 2250);
FORCEPROP 2 LAST PATH I236
J 0
(-375 2325);
DISPLAY 1.021277 (-375 2325);
PAINT ORANGE (-375 2325);
DISPLAY INVISIBLE (-375 2325);
FORCEPROP 2 LAST CDS_LIB mstr_standard
J 0
(-550 2250);
PAINT ORANGE (-550 2250);
DISPLAY INVISIBLE (-550 2250);
FORCEPROP 1 LAST OFFPAGE TRUE
J 0
(-225 2125);
DISPLAY 1.170213 (-225 2125);
PAINT GREEN (-225 2125);
DISPLAY INVISIBLE (-225 2125);
FORCEPROP 1 LAST COMMENT_BODY TRUE
J 0
(-595 2155);
DISPLAY 1.170213 (-595 2155);
PAINT PEACH (-595 2155);
DISPLAY INVISIBLE (-595 2155);
FORCEADD OFFPAGE..2
(-550 2200);
FORCEPROP 2 LAST $XR0 190 
J 0
(-361 2200);
DISPLAY 0.638298 (-361 2200);
PAINT MONO (-361 2200);
FORCEPROP 2 LAST PATH I237
J 0
(-375 2275);
DISPLAY 1.021277 (-375 2275);
PAINT ORANGE (-375 2275);
DISPLAY INVISIBLE (-375 2275);
FORCEPROP 2 LAST CDS_LIB mstr_standard
J 0
(-550 2200);
PAINT ORANGE (-550 2200);
DISPLAY INVISIBLE (-550 2200);
FORCEPROP 1 LAST OFFPAGE TRUE
J 0
(-225 2075);
DISPLAY 1.170213 (-225 2075);
PAINT GREEN (-225 2075);
DISPLAY INVISIBLE (-225 2075);
FORCEPROP 1 LAST COMMENT_BODY TRUE
J 0
(-595 2105);
DISPLAY 1.170213 (-595 2105);
PAINT PEACH (-595 2105);
DISPLAY INVISIBLE (-595 2105);
FORCEADD RES..2
(-700 2700);
FORCEPROP 1 LAST PART_NUMBER G21796-016
R 1
J 0
(-635 2575);
DISPLAY 0.617021 (-635 2575);
PAINT BLUE (-635 2575);
FORCEPROP 1 LAST WATTAGE 1/16W
J 0
(-610 2675);
DISPLAY 0.617021 (-610 2675);
PAINT SKYBLUE (-610 2675);
FORCEPROP 1 LAST LOCATION R5N1
J 0
(-605 2825);
DISPLAY 0.617021 (-605 2825);
PAINT AQUA (-605 2825);
FORCEPROP 1 LAST VALUE 10.0K
J 0
(-605 2775);
DISPLAY 0.617021 (-605 2775);
PAINT SKYBLUE (-605 2775);
FORCEPROP 1 LAST PACK_TYPE 0402
J 0
(-610 2575);
DISPLAY 0.617021 (-610 2575);
PAINT SKYBLUE (-610 2575);
FORCEPROP 1 LASTPIN (-700 2800) $PN 1
J 0
(-695 2762);
DISPLAY 0.617021 (-695 2762);
PAINT ORANGE (-695 2762);
FORCEPROP 1 LASTPIN (-700 2600) $PN 2
J 0
(-695 2610);
DISPLAY 0.617021 (-695 2610);
PAINT ORANGE (-695 2610);
FORCEPROP 1 LAST MATERIAL CHIP
J 0
(-610 2625);
DISPLAY 0.617021 (-610 2625);
PAINT SKYBLUE (-610 2625);
FORCEPROP 1 LAST TOLERANCE 1%
J 0
(-605 2725);
DISPLAY 0.617021 (-605 2725);
PAINT SKYBLUE (-605 2725);
FORCEPROP 2 LAST SEC_TYPE 0402
J 0
(-650 2925);
DISPLAY 1.021277 (-650 2925);
PAINT ORANGE (-650 2925);
DISPLAY INVISIBLE (-650 2925);
FORCEPROP 2 LAST SEC 1
J 0
(-650 2925);
DISPLAY 0.680851 (-650 2925);
PAINT MONO (-650 2925);
DISPLAY INVISIBLE (-650 2925);
FORCEPROP 2 LAST CDS_LOCATION R5N1
J 0
(-655 2825);
DISPLAY 0.617021 (-655 2825);
PAINT AQUA (-655 2825);
DISPLAY INVISIBLE (-655 2825);
FORCEPROP 1 LAST PATH I238
J 0
(-650 2875);
DISPLAY 0.978723 (-650 2875);
PAINT WHITE (-650 2875);
DISPLAY INVISIBLE (-650 2875);
FORCEPROP 2 LAST BOM_COST PROC_SIDEBAND
J 0
(-700 2700);
PAINT WHITE (-700 2700);
DISPLAY INVISIBLE (-700 2700);
FORCEPROP 2 LAST CDS_LIB mstr_discrete
J 2
(-700 2700);
PAINT ORANGE (-700 2700);
DISPLAY INVISIBLE (-700 2700);
FORCEPROP 2 LAST ROOM CPU0
J 0
(-675 2475);
PAINT WHITE (-675 2475);
DISPLAY INVISIBLE (-675 2475);
FORCEADD RES..2
(-950 2700);
FORCEPROP 1 LAST PART_NUMBER G21796-016
R 1
J 0
(-885 2575);
DISPLAY 0.617021 (-885 2575);
PAINT BLUE (-885 2575);
FORCEPROP 1 LAST WATTAGE 1/16W
J 0
(-860 2675);
DISPLAY 0.617021 (-860 2675);
PAINT SKYBLUE (-860 2675);
FORCEPROP 1 LASTPIN (-950 2600) $PN 2
J 0
(-945 2610);
DISPLAY 0.617021 (-945 2610);
PAINT ORANGE (-945 2610);
FORCEPROP 1 LAST PACK_TYPE 0402
J 0
(-860 2575);
DISPLAY 0.617021 (-860 2575);
PAINT SKYBLUE (-860 2575);
FORCEPROP 1 LAST VALUE 10.0K
J 0
(-855 2775);
DISPLAY 0.617021 (-855 2775);
PAINT SKYBLUE (-855 2775);
FORCEPROP 1 LAST TOLERANCE 1%
J 0
(-855 2725);
DISPLAY 0.617021 (-855 2725);
PAINT SKYBLUE (-855 2725);
FORCEPROP 1 LASTPIN (-950 2800) $PN 1
J 0
(-945 2762);
DISPLAY 0.617021 (-945 2762);
PAINT ORANGE (-945 2762);
FORCEPROP 1 LAST MATERIAL CHIP
J 0
(-860 2625);
DISPLAY 0.617021 (-860 2625);
PAINT SKYBLUE (-860 2625);
FORCEPROP 1 LAST LOCATION R5N5
J 0
(-855 2825);
DISPLAY 0.617021 (-855 2825);
PAINT AQUA (-855 2825);
FORCEPROP 2 LAST SEC 1
J 0
(-900 2925);
DISPLAY 0.680851 (-900 2925);
PAINT MONO (-900 2925);
DISPLAY INVISIBLE (-900 2925);
FORCEPROP 2 LAST SEC_TYPE 0402
J 0
(-900 2925);
DISPLAY 1.021277 (-900 2925);
PAINT ORANGE (-900 2925);
DISPLAY INVISIBLE (-900 2925);
FORCEPROP 2 LAST CDS_LOCATION R5N5
J 0
(-905 2825);
DISPLAY 0.617021 (-905 2825);
PAINT AQUA (-905 2825);
DISPLAY INVISIBLE (-905 2825);
FORCEPROP 1 LAST PATH I239
J 0
(-900 2875);
DISPLAY 0.978723 (-900 2875);
PAINT WHITE (-900 2875);
DISPLAY INVISIBLE (-900 2875);
FORCEPROP 2 LAST CDS_LIB mstr_discrete
J 2
(-950 2700);
PAINT ORANGE (-950 2700);
DISPLAY INVISIBLE (-950 2700);
FORCEPROP 2 LAST BOM_COST PROC_SIDEBAND
J 0
(-950 2700);
PAINT WHITE (-950 2700);
DISPLAY INVISIBLE (-950 2700);
FORCEPROP 2 LAST ROOM CPU0
J 0
(-925 2475);
PAINT WHITE (-925 2475);
DISPLAY INVISIBLE (-925 2475);
FORCEADD RES..2
(-1200 2700);
FORCEPROP 1 LAST MATERIAL CHIP
J 0
(-1110 2625);
DISPLAY 0.617021 (-1110 2625);
PAINT SKYBLUE (-1110 2625);
FORCEPROP 1 LAST WATTAGE 1/16W
J 0
(-1110 2675);
DISPLAY 0.617021 (-1110 2675);
PAINT SKYBLUE (-1110 2675);
FORCEPROP 1 LAST VALUE 10.0K
J 0
(-1105 2775);
DISPLAY 0.617021 (-1105 2775);
PAINT SKYBLUE (-1105 2775);
FORCEPROP 1 LAST LOCATION R5N3
J 0
(-1105 2825);
DISPLAY 0.617021 (-1105 2825);
PAINT AQUA (-1105 2825);
FORCEPROP 1 LAST PART_NUMBER G21796-016
R 1
J 0
(-1135 2575);
DISPLAY 0.617021 (-1135 2575);
PAINT BLUE (-1135 2575);
FORCEPROP 1 LAST TOLERANCE 1%
J 0
(-1105 2725);
DISPLAY 0.617021 (-1105 2725);
PAINT SKYBLUE (-1105 2725);
FORCEPROP 1 LASTPIN (-1200 2600) $PN 2
J 0
(-1195 2610);
DISPLAY 0.617021 (-1195 2610);
PAINT ORANGE (-1195 2610);
FORCEPROP 1 LASTPIN (-1200 2800) $PN 1
J 0
(-1195 2762);
DISPLAY 0.617021 (-1195 2762);
PAINT ORANGE (-1195 2762);
FORCEPROP 1 LAST PACK_TYPE 0402
J 0
(-1110 2575);
DISPLAY 0.617021 (-1110 2575);
PAINT SKYBLUE (-1110 2575);
FORCEPROP 1 LAST PATH I240
J 0
(-1150 2875);
DISPLAY 0.978723 (-1150 2875);
PAINT WHITE (-1150 2875);
DISPLAY INVISIBLE (-1150 2875);
FORCEPROP 2 LAST SEC 1
J 0
(-1150 2925);
DISPLAY 0.680851 (-1150 2925);
PAINT MONO (-1150 2925);
DISPLAY INVISIBLE (-1150 2925);
FORCEPROP 2 LAST SEC_TYPE 0402
J 0
(-1150 2925);
DISPLAY 1.021277 (-1150 2925);
PAINT ORANGE (-1150 2925);
DISPLAY INVISIBLE (-1150 2925);
FORCEPROP 2 LAST CDS_LOCATION R5N3
J 0
(-1155 2825);
DISPLAY 0.617021 (-1155 2825);
PAINT AQUA (-1155 2825);
DISPLAY INVISIBLE (-1155 2825);
FORCEPROP 2 LAST CDS_LIB mstr_discrete
J 2
(-1200 2700);
PAINT ORANGE (-1200 2700);
DISPLAY INVISIBLE (-1200 2700);
FORCEPROP 2 LAST BOM_COST PROC_SIDEBAND
J 0
(-1200 2700);
PAINT WHITE (-1200 2700);
DISPLAY INVISIBLE (-1200 2700);
FORCEPROP 2 LAST ROOM CPU0
J 0
(-1175 2475);
PAINT WHITE (-1175 2475);
DISPLAY INVISIBLE (-1175 2475);
FORCEADD RES..2
(-1450 2700);
FORCEPROP 1 LAST MATERIAL CHIP
J 0
(-1360 2625);
DISPLAY 0.617021 (-1360 2625);
PAINT SKYBLUE (-1360 2625);
FORCEPROP 1 LAST PACK_TYPE 0402
J 0
(-1360 2575);
DISPLAY 0.617021 (-1360 2575);
PAINT SKYBLUE (-1360 2575);
FORCEPROP 1 LASTPIN (-1450 2600) $PN 2
J 0
(-1445 2610);
DISPLAY 0.617021 (-1445 2610);
PAINT ORANGE (-1445 2610);
FORCEPROP 1 LASTPIN (-1450 2800) $PN 1
J 0
(-1445 2762);
DISPLAY 0.617021 (-1445 2762);
PAINT ORANGE (-1445 2762);
FORCEPROP 1 LAST PART_NUMBER G21796-336
R 1
J 0
(-1385 2575);
DISPLAY 0.617021 (-1385 2575);
PAINT BLUE (-1385 2575);
FORCEPROP 1 LAST LOCATION R5N4
J 0
(-1355 2825);
DISPLAY 0.617021 (-1355 2825);
PAINT AQUA (-1355 2825);
FORCEPROP 1 LAST VALUE 1.8K
J 0
(-1355 2775);
DISPLAY 0.617021 (-1355 2775);
PAINT SKYBLUE (-1355 2775);
FORCEPROP 1 LAST TOLERANCE 1%
J 0
(-1355 2725);
DISPLAY 0.617021 (-1355 2725);
PAINT SKYBLUE (-1355 2725);
FORCEPROP 1 LAST WATTAGE 1/16W
J 0
(-1360 2675);
DISPLAY 0.617021 (-1360 2675);
PAINT SKYBLUE (-1360 2675);
FORCEPROP 2 LAST SEC 1
J 0
(-1400 2925);
DISPLAY 0.680851 (-1400 2925);
PAINT MONO (-1400 2925);
DISPLAY INVISIBLE (-1400 2925);
FORCEPROP 2 LAST CDS_LOCATION R5N4
J 0
(-1405 2825);
DISPLAY 0.617021 (-1405 2825);
PAINT AQUA (-1405 2825);
DISPLAY INVISIBLE (-1405 2825);
FORCEPROP 1 LAST PATH I241
J 0
(-1400 2875);
DISPLAY 0.978723 (-1400 2875);
PAINT WHITE (-1400 2875);
DISPLAY INVISIBLE (-1400 2875);
FORCEPROP 2 LAST SEC_TYPE 0402
J 0
(-1400 2925);
DISPLAY 1.021277 (-1400 2925);
PAINT ORANGE (-1400 2925);
DISPLAY INVISIBLE (-1400 2925);
FORCEPROP 2 LAST CDS_LIB mstr_discrete
J 2
(-1450 2700);
PAINT ORANGE (-1450 2700);
DISPLAY INVISIBLE (-1450 2700);
FORCEPROP 2 LAST BOM_COST PROC_SIDEBAND
J 0
(-1450 2700);
PAINT WHITE (-1450 2700);
DISPLAY INVISIBLE (-1450 2700);
FORCEPROP 2 LAST ROOM CPU0
J 0
(-1425 2475);
PAINT WHITE (-1425 2475);
DISPLAY INVISIBLE (-1425 2475);
FORCEADD P3V3_STBY..1
(-1075 1725);
FORCEPROP 3 LASTPIN (-1075 1675) SIG_NAME P3V3_STBY\g
J 0
(-1065 1685);
DISPLAY 0.659574 (-1065 1685);
PAINT MONO (-1065 1685);
DISPLAY INVISIBLE (-1065 1685);
FORCEPROP 1 LAST VOLTAGE 3.3V
J 0
(-1120 1682);
DISPLAY 0.340426 (-1120 1682);
PAINT SKYBLUE (-1120 1682);
DISPLAY INVISIBLE (-1120 1682);
FORCEPROP 2 LAST CDS_LIB mstr_symbols
J 0
(-1075 1725);
PAINT ORANGE (-1075 1725);
DISPLAY INVISIBLE (-1075 1725);
FORCEPROP 1 LAST SIZE 1B
J 0
(-1030 1747);
DISPLAY 0.340426 (-1030 1747);
PAINT GREEN (-1030 1747);
DISPLAY INVISIBLE (-1030 1747);
FORCEPROP 1 LAST PATH I243
J 0
(-1030 1727);
DISPLAY 0.340426 (-1030 1727);
PAINT GREEN (-1030 1727);
DISPLAY INVISIBLE (-1030 1727);
FORCEPROP 1 LAST BODY_TYPE PLUMBING
J 0
(-1120 1682);
DISPLAY 0.340426 (-1120 1682);
PAINT GREEN (-1120 1682);
DISPLAY INVISIBLE (-1120 1682);
FORCEPROP 1 LAST HDL_POWER P3V3_STBY
J 0
(-1375 1600);
DISPLAY 0.872340 (-1375 1600);
PAINT GREEN (-1375 1600);
DISPLAY INVISIBLE (-1375 1600);
FORCEADD RES..1
(-2075 4250);
FORCEPROP 1 LAST PACK_TYPE 0402
J 0
(-1875 4300);
DISPLAY 0.617021 (-1875 4300);
PAINT SKYBLUE (-1875 4300);
FORCEPROP 1 LAST MATERIAL CHIP
J 0
(-2000 4300);
DISPLAY 0.617021 (-2000 4300);
PAINT SKYBLUE (-2000 4300);
FORCEPROP 1 LASTPIN (-1975 4250) $PN 2
J 0
(-2013 4262);
DISPLAY 0.617021 (-2013 4262);
PAINT ORANGE (-2013 4262);
FORCEPROP 1 LAST WATTAGE 1/16W
J 2
(-2025 4300);
DISPLAY 0.617021 (-2025 4300);
PAINT SKYBLUE (-2025 4300);
FORCEPROP 1 LASTPIN (-2175 4250) $PN 1
J 0
(-2163 4262);
DISPLAY 0.617021 (-2163 4262);
PAINT ORANGE (-2163 4262);
FORCEPROP 1 LAST TOLERANCE 1%
J 0
(-2225 4300);
DISPLAY 0.617021 (-2225 4300);
PAINT SKYBLUE (-2225 4300);
FORCEPROP 1 LAST VALUE 49.9
J 2
(-2250 4300);
DISPLAY 0.617021 (-2250 4300);
PAINT SKYBLUE (-2250 4300);
FORCEPROP 1 LAST LOCATION R4P18
J 0
(-2475 4300);
DISPLAY 0.617021 (-2475 4300);
PAINT AQUA (-2475 4300);
FORCEPROP 1 LAST PART_NUMBER G21796-047
J 0
(-1750 4300);
DISPLAY 0.617021 (-1750 4300);
PAINT BLUE (-1750 4300);
FORCEPROP 2 LAST SEC_TYPE 0402
J 0
(-2125 4450);
DISPLAY 1.021277 (-2125 4450);
PAINT ORANGE (-2125 4450);
DISPLAY INVISIBLE (-2125 4450);
FORCEPROP 0 LAST BOM_COST PROC_SIDEBAND
J 0
(-2125 4375);
DISPLAY 1.021277 (-2125 4375);
PAINT ORANGE (-2125 4375);
DISPLAY INVISIBLE (-2125 4375);
FORCEPROP 2 LAST SEC 1
J 0
(-2125 4450);
DISPLAY 0.680851 (-2125 4450);
PAINT MONO (-2125 4450);
DISPLAY INVISIBLE (-2125 4450);
FORCEPROP 1 LAST PATH I244
J 0
(-2125 4400);
DISPLAY 0.978723 (-2125 4400);
PAINT WHITE (-2125 4400);
DISPLAY INVISIBLE (-2125 4400);
FORCEPROP 0 LAST ROOM CPU0
J 0
(-2125 4375);
DISPLAY 1.021277 (-2125 4375);
PAINT ORANGE (-2125 4375);
DISPLAY INVISIBLE (-2125 4375);
FORCEPROP 2 LAST CDS_LIB mstr_discrete
J 0
(-2075 4250);
PAINT ORANGE (-2075 4250);
DISPLAY INVISIBLE (-2075 4250);
FORCEPROP 2 LAST CDS_LOCATION R4P18
J 0
(-2125 4275);
DISPLAY 0.617021 (-2125 4275);
PAINT AQUA (-2125 4275);
DISPLAY INVISIBLE (-2125 4275);
FORCEADD OFFPAGE..1
R 2
(-1800 1650);
FORCEPROP 2 LAST $XR0 90 
J 0
(-1614 1650);
DISPLAY 0.638298 (-1614 1650);
PAINT MONO (-1614 1650);
FORCEPROP 2 LAST PATH I247
J 0
(-1600 1700);
DISPLAY 1.021277 (-1600 1700);
PAINT ORANGE (-1600 1700);
DISPLAY INVISIBLE (-1600 1700);
FORCEPROP 2 LAST CDS_LIB mstr_standard
J 0
(-1800 1650);
PAINT MONO (-1800 1650);
DISPLAY INVISIBLE (-1800 1650);
FORCEPROP 1 LAST OFFPAGE TRUE
J 2
(-2125 1525);
DISPLAY 0.872340 (-2125 1525);
PAINT GREEN (-2125 1525);
DISPLAY INVISIBLE (-2125 1525);
FORCEPROP 1 LAST COMMENT_BODY TRUE
J 2
(-1925 1550);
DISPLAY 0.872340 (-1925 1550);
PAINT GREEN (-1925 1550);
DISPLAY INVISIBLE (-1925 1550);
FORCEADD OFFPAGE..1
R 2
(-1800 1600);
FORCEPROP 2 LAST $XR0 90 
J 0
(-1614 1600);
DISPLAY 0.638298 (-1614 1600);
PAINT MONO (-1614 1600);
FORCEPROP 2 LAST PATH I254
J 0
(-1625 1675);
DISPLAY 1.021277 (-1625 1675);
PAINT ORANGE (-1625 1675);
DISPLAY INVISIBLE (-1625 1675);
FORCEPROP 2 LAST CDS_LIB mstr_standard
J 0
(-1800 1600);
PAINT ORANGE (-1800 1600);
DISPLAY INVISIBLE (-1800 1600);
FORCEPROP 1 LAST OFFPAGE TRUE
J 2
(-2125 1475);
DISPLAY 0.872340 (-2125 1475);
PAINT GREEN (-2125 1475);
DISPLAY INVISIBLE (-2125 1475);
FORCEPROP 1 LAST COMMENT_BODY TRUE
J 2
(-1925 1500);
DISPLAY 0.872340 (-1925 1500);
PAINT GREEN (-1925 1500);
DISPLAY INVISIBLE (-1925 1500);
FORCEADD OFFPAGE..1
R 2
(-1800 1550);
FORCEPROP 2 LAST $XR0 90 
J 0
(-1614 1550);
DISPLAY 0.638298 (-1614 1550);
PAINT MONO (-1614 1550);
FORCEPROP 2 LAST PATH I255
J 0
(-1625 1625);
DISPLAY 1.021277 (-1625 1625);
PAINT ORANGE (-1625 1625);
DISPLAY INVISIBLE (-1625 1625);
FORCEPROP 2 LAST CDS_LIB mstr_standard
J 0
(-1800 1550);
PAINT ORANGE (-1800 1550);
DISPLAY INVISIBLE (-1800 1550);
FORCEPROP 1 LAST OFFPAGE TRUE
J 2
(-2125 1425);
DISPLAY 0.872340 (-2125 1425);
PAINT GREEN (-2125 1425);
DISPLAY INVISIBLE (-2125 1425);
FORCEPROP 1 LAST COMMENT_BODY TRUE
J 2
(-1925 1450);
DISPLAY 0.872340 (-1925 1450);
PAINT GREEN (-1925 1450);
DISPLAY INVISIBLE (-1925 1450);
FORCEADD OFFPAGE..1
R 2
(-1800 1500);
FORCEPROP 2 LAST $XR0 90 
J 0
(-1614 1500);
DISPLAY 0.638298 (-1614 1500);
PAINT MONO (-1614 1500);
FORCEPROP 2 LAST PATH I256
J 0
(-1625 1575);
DISPLAY 1.021277 (-1625 1575);
PAINT ORANGE (-1625 1575);
DISPLAY INVISIBLE (-1625 1575);
FORCEPROP 2 LAST CDS_LIB mstr_standard
J 0
(-1800 1500);
PAINT ORANGE (-1800 1500);
DISPLAY INVISIBLE (-1800 1500);
FORCEPROP 1 LAST OFFPAGE TRUE
J 2
(-2125 1375);
DISPLAY 0.872340 (-2125 1375);
PAINT GREEN (-2125 1375);
DISPLAY INVISIBLE (-2125 1375);
FORCEPROP 1 LAST COMMENT_BODY TRUE
J 2
(-1925 1400);
DISPLAY 0.872340 (-1925 1400);
PAINT GREEN (-1925 1400);
DISPLAY INVISIBLE (-1925 1400);
FORCEADD PVCCIO_CPU0..1
(-375 3400);
FORCEPROP 3 LASTPIN (-375 3350) SIG_NAME PVCCIO_CPU0\g
J 0
(-365 3360);
DISPLAY 0.659574 (-365 3360);
PAINT MONO (-365 3360);
DISPLAY INVISIBLE (-365 3360);
FORCEPROP 1 LAST VOLTAGE 1.1V
J 0
(-420 3357);
DISPLAY 0.340426 (-420 3357);
PAINT SKYBLUE (-420 3357);
DISPLAY INVISIBLE (-420 3357);
FORCEPROP 2 LAST CDS_LIB mstr_symbols
J 0
(-375 3400);
PAINT ORANGE (-375 3400);
DISPLAY INVISIBLE (-375 3400);
FORCEPROP 1 LAST PATH I257
J 0
(-325 3425);
DISPLAY 0.872340 (-325 3425);
PAINT AQUA (-325 3425);
DISPLAY INVISIBLE (-325 3425);
FORCEPROP 1 LAST BODY_TYPE PLUMBING
J 0
(-420 3357);
DISPLAY 0.340426 (-420 3357);
PAINT GREEN (-420 3357);
DISPLAY INVISIBLE (-420 3357);
FORCEPROP 1 LAST HDL_POWER PVCCIO_CPU0
J 1
(-375 3450);
DISPLAY 0.872340 (-375 3450);
PAINT GREEN (-375 3450);
DISPLAY INVISIBLE (-375 3450);
FORCEADD RES..2
(-1075 1450);
FORCEPROP 1 LAST TOLERANCE 1%
J 0
(-1030 1475);
DISPLAY 0.617021 (-1030 1475);
PAINT SKYBLUE (-1030 1475);
FORCEPROP 1 LAST LOCATION R4R5
J 0
(-1030 1575);
DISPLAY 0.617021 (-1030 1575);
PAINT AQUA (-1030 1575);
FORCEPROP 1 LAST MATERIAL CHIP
J 0
(-1035 1375);
DISPLAY 0.617021 (-1035 1375);
PAINT SKYBLUE (-1035 1375);
FORCEPROP 1 LAST PART_NUMBER G21796-072
J 0
(-1035 1325);
DISPLAY 0.617021 (-1035 1325);
PAINT BLUE (-1035 1325);
FORCEPROP 1 LAST PACK_TYPE 0402
J 0
(-1035 1275);
DISPLAY 0.617021 (-1035 1275);
PAINT SKYBLUE (-1035 1275);
FORCEPROP 1 LAST WATTAGE 1/16W
J 0
(-1035 1425);
DISPLAY 0.617021 (-1035 1425);
PAINT SKYBLUE (-1035 1425);
FORCEPROP 1 LASTPIN (-1075 1550) $PN 1
J 0
(-1070 1512);
DISPLAY 0.617021 (-1070 1512);
PAINT ORANGE (-1070 1512);
FORCEPROP 1 LASTPIN (-1075 1350) $PN 2
J 0
(-1070 1360);
DISPLAY 0.617021 (-1070 1360);
PAINT ORANGE (-1070 1360);
FORCEPROP 1 LAST VALUE 4.75K
J 0
(-1030 1525);
DISPLAY 0.617021 (-1030 1525);
PAINT SKYBLUE (-1030 1525);
FORCEPROP 2 LAST SEC_TYPE 0402
J 0
(-1025 1675);
DISPLAY 1.021277 (-1025 1675);
PAINT ORANGE (-1025 1675);
DISPLAY INVISIBLE (-1025 1675);
FORCEPROP 2 LAST SEC 1
J 0
(-1025 1675);
DISPLAY 0.680851 (-1025 1675);
PAINT MONO (-1025 1675);
DISPLAY INVISIBLE (-1025 1675);
FORCEPROP 0 LAST ROOM CPU0
J 0
(-1025 1675);
DISPLAY 1.021277 (-1025 1675);
PAINT ORANGE (-1025 1675);
DISPLAY INVISIBLE (-1025 1675);
FORCEPROP 1 LAST PATH I258
J 0
(-1025 1625);
DISPLAY 0.978723 (-1025 1625);
PAINT WHITE (-1025 1625);
DISPLAY INVISIBLE (-1025 1625);
FORCEPROP 2 LAST CDS_LOCATION R4R5
J 0
(-1030 1575);
DISPLAY 0.617021 (-1030 1575);
PAINT AQUA (-1030 1575);
DISPLAY INVISIBLE (-1030 1575);
FORCEPROP 2 LAST CDS_LIB mstr_discrete
J 0
(-1075 1450);
PAINT ORANGE (-1075 1450);
DISPLAY INVISIBLE (-1075 1450);
FORCEADD SKX_EXT_B..1
(-4075 2850);
FORCEPROP 2 LASTPIN (-3125 2600) $PN AU22
J 0
(-3115 2610);
DISPLAY 0.617021 (-3115 2610);
PAINT ORANGE (-3115 2610);
FORCEPROP 2 LASTPIN (-3125 2550) $PN AU20
J 0
(-3115 2560);
DISPLAY 0.617021 (-3115 2560);
PAINT ORANGE (-3115 2560);
FORCEPROP 2 LASTPIN (-3125 4500) $PN BC24
J 0
(-3115 4510);
DISPLAY 0.617021 (-3115 4510);
PAINT ORANGE (-3115 4510);
FORCEPROP 2 LASTPIN (-3125 4350) $PN AJ14
J 0
(-3115 4360);
DISPLAY 0.617021 (-3115 4360);
PAINT ORANGE (-3115 4360);
FORCEPROP 2 LASTPIN (-3125 4100) $PN AU12
J 0
(-3115 4110);
DISPLAY 0.617021 (-3115 4110);
PAINT ORANGE (-3115 4110);
FORCEPROP 2 LASTPIN (-3125 4250) $PN AR14
J 0
(-3115 4260);
DISPLAY 0.617021 (-3115 4260);
PAINT ORANGE (-3115 4260);
FORCEPROP 2 LASTPIN (-3125 4200) $PN AT19
J 0
(-3115 4210);
DISPLAY 0.617021 (-3115 4210);
PAINT ORANGE (-3115 4210);
FORCEPROP 2 LASTPIN (-3125 4450) $PN AP21
J 0
(-3115 4460);
DISPLAY 0.617021 (-3115 4460);
PAINT ORANGE (-3115 4460);
FORCEPROP 2 LASTPIN (-3125 2800) $PN BA20
J 0
(-3115 2810);
DISPLAY 0.617021 (-3115 2810);
PAINT ORANGE (-3115 2810);
FORCEPROP 2 LASTPIN (-3125 2950) $PN BD23
J 0
(-3115 2960);
DISPLAY 0.617021 (-3115 2960);
PAINT ORANGE (-3115 2960);
FORCEPROP 2 LASTPIN (-3125 3650) $PN AL14
J 0
(-3115 3660);
DISPLAY 0.617021 (-3115 3660);
PAINT ORANGE (-3115 3660);
FORCEPROP 2 LASTPIN (-3125 3450) $PN AJ12
J 0
(-3115 3460);
DISPLAY 0.617021 (-3115 3460);
PAINT ORANGE (-3115 3460);
FORCEPROP 2 LASTPIN (-3125 3500) $PN AK11
J 0
(-3115 3510);
DISPLAY 0.617021 (-3115 3510);
PAINT ORANGE (-3115 3510);
FORCEPROP 2 LASTPIN (-3125 3550) $PN AL12
J 0
(-3115 3560);
DISPLAY 0.617021 (-3115 3560);
PAINT ORANGE (-3115 3560);
FORCEPROP 2 LASTPIN (-3125 3000) $PN AV17
J 0
(-3115 3010);
DISPLAY 0.617021 (-3115 3010);
PAINT ORANGE (-3115 3010);
FORCEPROP 2 LASTPIN (-3125 3350) $PN AN20
J 0
(-3115 3360);
DISPLAY 0.617021 (-3115 3360);
PAINT ORANGE (-3115 3360);
FORCEPROP 2 LASTPIN (-3125 2200) $PN DC72
J 0
(-3115 2210);
DISPLAY 0.617021 (-3115 2210);
PAINT ORANGE (-3115 2210);
FORCEPROP 2 LASTPIN (-3125 2250) $PN CW72
J 0
(-3115 2260);
DISPLAY 0.617021 (-3115 2260);
PAINT ORANGE (-3115 2260);
FORCEPROP 2 LASTPIN (-3125 2750) $PN AF15
J 0
(-3115 2760);
DISPLAY 0.617021 (-3115 2760);
PAINT ORANGE (-3115 2760);
FORCEPROP 2 LASTPIN (-3125 3250) $PN AB17
J 0
(-3115 3260);
DISPLAY 0.617021 (-3115 3260);
PAINT ORANGE (-3115 3260);
FORCEPROP 2 LASTPIN (-3125 3200) $PN AC16
J 0
(-3115 3210);
DISPLAY 0.617021 (-3115 3210);
PAINT ORANGE (-3115 3210);
FORCEPROP 2 LASTPIN (-3125 3050) $PN AR18
J 0
(-3115 3060);
DISPLAY 0.617021 (-3115 3060);
PAINT ORANGE (-3115 3060);
FORCEPROP 2 LASTPIN (-3125 2050) $PN CV59
J 0
(-3115 2060);
DISPLAY 0.617021 (-3115 2060);
PAINT ORANGE (-3115 2060);
FORCEPROP 2 LASTPIN (-3125 2650) $PN AU16
J 0
(-3115 2660);
DISPLAY 0.617021 (-3115 2660);
PAINT ORANGE (-3115 2660);
FORCEPROP 2 LASTPIN (-3125 3750) $PN DE44
J 0
(-3115 3760);
DISPLAY 0.617021 (-3115 3760);
PAINT ORANGE (-3115 3760);
FORCEPROP 2 LASTPIN (-3125 3800) $PN DC44
J 0
(-3115 3810);
DISPLAY 0.617021 (-3115 3810);
PAINT ORANGE (-3115 3810);
FORCEPROP 2 LASTPIN (-3125 3950) $PN DG44
J 0
(-3115 3960);
DISPLAY 0.617021 (-3115 3960);
PAINT ORANGE (-3115 3960);
FORCEPROP 2 LASTPIN (-3125 3850) $PN DB45
J 0
(-3115 3860);
DISPLAY 0.617021 (-3115 3860);
PAINT ORANGE (-3115 3860);
FORCEPROP 2 LASTPIN (-3125 4000) $PN DJ44
J 0
(-3115 4010);
DISPLAY 0.617021 (-3115 4010);
PAINT ORANGE (-3115 4010);
FORCEPROP 2 LASTPIN (-3125 3150) $PN AB15
J 0
(-3115 3160);
DISPLAY 0.617021 (-3115 3160);
PAINT ORANGE (-3115 3160);
FORCEPROP 2 LASTPIN (-3125 2100) $PN AM11
J 0
(-3115 2110);
DISPLAY 0.617021 (-3115 2110);
PAINT ORANGE (-3115 2110);
FORCEPROP 2 LASTPIN (-3125 2900) $PN AW18
J 0
(-3115 2910);
DISPLAY 0.617021 (-3115 2910);
PAINT ORANGE (-3115 2910);
FORCEPROP 2 LASTPIN (-3125 2850) $PN AV15
J 0
(-3115 2860);
DISPLAY 0.617021 (-3115 2860);
PAINT ORANGE (-3115 2860);
FORCEPROP 2 LASTPIN (-3125 2300) $PN DA72
J 0
(-3115 2310);
DISPLAY 0.617021 (-3115 2310);
PAINT ORANGE (-3115 2310);
FORCEPROP 2 LASTPIN (-3125 2400) $PN CY71
J 0
(-3115 2410);
DISPLAY 0.617021 (-3115 2410);
PAINT ORANGE (-3115 2410);
FORCEPROP 2 LASTPIN (-3125 2450) $PN DB71
J 0
(-3115 2460);
DISPLAY 0.617021 (-3115 2460);
PAINT ORANGE (-3115 2460);
FORCEPROP 2 LASTPIN (-3125 1750) $PN CV57
J 0
(-3115 1760);
DISPLAY 0.617021 (-3115 1760);
PAINT ORANGE (-3115 1760);
FORCEPROP 2 LASTPIN (-3125 1900) $PN AE20
J 0
(-3115 1910);
DISPLAY 0.617021 (-3115 1910);
PAINT ORANGE (-3115 1910);
FORCEPROP 2 LASTPIN (-3125 1950) $PN AP11
J 0
(-3115 1960);
DISPLAY 0.617021 (-3115 1960);
PAINT ORANGE (-3115 1960);
FORCEPROP 2 LASTPIN (-3125 1350) $PN AG16
J 0
(-3115 1360);
DISPLAY 0.617021 (-3115 1360);
PAINT ORANGE (-3115 1360);
FORCEPROP 2 LASTPIN (-3125 1400) $PN AR12
J 0
(-3115 1410);
DISPLAY 0.617021 (-3115 1410);
PAINT ORANGE (-3115 1410);
FORCEPROP 2 LASTPIN (-3125 1150) $PN AE14
J 0
(-3115 1160);
DISPLAY 0.617021 (-3115 1160);
PAINT ORANGE (-3115 1160);
FORCEPROP 2 LASTPIN (-3125 1550) $PN DB51
J 0
(-3115 1560);
DISPLAY 0.617021 (-3115 1560);
PAINT ORANGE (-3115 1560);
FORCEPROP 2 LASTPIN (-3125 1800) $PN CW56
J 0
(-3115 1810);
DISPLAY 0.617021 (-3115 1810);
PAINT ORANGE (-3115 1810);
FORCEPROP 2 LASTPIN (-3125 1250) $PN AB13
J 0
(-3115 1260);
DISPLAY 0.617021 (-3115 1260);
PAINT ORANGE (-3115 1260);
FORCEPROP 2 LASTPIN (-3125 1650) $PN AW14
J 0
(-3115 1660);
DISPLAY 0.617021 (-3115 1660);
PAINT ORANGE (-3115 1660);
FORCEPROP 2 LASTPIN (-3125 1600) $PN DC50
J 0
(-3115 1610);
DISPLAY 0.617021 (-3115 1610);
PAINT ORANGE (-3115 1610);
FORCEPROP 2 LASTPIN (-3125 1700) $PN CU58
J 0
(-3115 1710);
DISPLAY 0.617021 (-3115 1710);
PAINT ORANGE (-3115 1710);
FORCEPROP 1 LAST LOCATION U5D1
J 0
(-4975 4750);
DISPLAY 0.617021 (-4975 4750);
PAINT AQUA (-4975 4750);
FORCEPROP 1 LAST MATERIAL IC
J 0
(-4975 4700);
DISPLAY 0.617021 (-4975 4700);
PAINT SKYBLUE (-4975 4700);
FORCEPROP 2 LASTPIN (-5025 4300) $PN CR26
J 2
(-5035 4310);
DISPLAY 0.617021 (-5035 4310);
PAINT ORANGE (-5035 4310);
FORCEPROP 2 LASTPIN (-5025 4350) $PN CP27
J 2
(-5035 4360);
DISPLAY 0.617021 (-5035 4360);
PAINT ORANGE (-5035 4360);
FORCEPROP 2 LASTPIN (-5025 4150) $PN CT25
J 2
(-5035 4160);
DISPLAY 0.617021 (-5035 4160);
PAINT ORANGE (-5035 4160);
FORCEPROP 2 LASTPIN (-5025 4200) $PN CU26
J 2
(-5035 4210);
DISPLAY 0.617021 (-5035 4210);
PAINT ORANGE (-5035 4210);
FORCEPROP 2 LASTPIN (-5025 4500) $PN AW24
J 2
(-5035 4510);
DISPLAY 0.617021 (-5035 4510);
PAINT ORANGE (-5035 4510);
FORCEPROP 2 LASTPIN (-5025 4450) $PN AU24
J 2
(-5035 4460);
DISPLAY 0.617021 (-5035 4460);
PAINT ORANGE (-5035 4460);
FORCEPROP 2 LASTPIN (-5025 2650) $PN AM19
J 2
(-5035 2660);
DISPLAY 0.617021 (-5035 2660);
PAINT ORANGE (-5035 2660);
FORCEPROP 2 LASTPIN (-5025 3350) $PN AJ64
J 2
(-5035 3360);
DISPLAY 0.617021 (-5035 3360);
PAINT ORANGE (-5035 3360);
FORCEPROP 2 LASTPIN (-5025 3400) $PN AK63
J 2
(-5035 3410);
DISPLAY 0.617021 (-5035 3410);
PAINT ORANGE (-5035 3410);
FORCEPROP 2 LASTPIN (-5025 3450) $PN AH63
J 2
(-5035 3460);
DISPLAY 0.617021 (-5035 3460);
PAINT ORANGE (-5035 3460);
FORCEPROP 2 LASTPIN (-5025 3500) $PN CP61
J 2
(-5035 3510);
DISPLAY 0.617021 (-5035 3510);
PAINT ORANGE (-5035 3510);
FORCEPROP 2 LASTPIN (-5025 3550) $PN CT61
J 2
(-5035 3560);
DISPLAY 0.617021 (-5035 3560);
PAINT ORANGE (-5035 3560);
FORCEPROP 2 LASTPIN (-5025 4050) $PN AN30
J 2
(-5035 4060);
DISPLAY 0.617021 (-5035 4060);
PAINT ORANGE (-5035 4060);
FORCEPROP 2 LASTPIN (-5025 3150) $PN Y43
J 2
(-5035 3160);
DISPLAY 0.617021 (-5035 3160);
PAINT ORANGE (-5035 3160);
FORCEPROP 2 LASTPIN (-5025 3250) $PN AC42
J 2
(-5035 3260);
DISPLAY 0.617021 (-5035 3260);
PAINT ORANGE (-5035 3260);
FORCEPROP 2 LASTPIN (-5025 2850) $PN AF17
J 2
(-5035 2860);
DISPLAY 0.617021 (-5035 2860);
PAINT ORANGE (-5035 2860);
FORCEPROP 2 LASTPIN (-5025 4000) $PN CR28
J 2
(-5035 4010);
DISPLAY 0.617021 (-5035 4010);
PAINT ORANGE (-5035 4010);
FORCEPROP 2 LASTPIN (-5025 3000) $PN DC48
J 2
(-5035 3010);
DISPLAY 0.617021 (-5035 3010);
PAINT ORANGE (-5035 3010);
FORCEPROP 2 LASTPIN (-5025 3050) $PN DD47
J 2
(-5035 3060);
DISPLAY 0.617021 (-5035 3060);
PAINT ORANGE (-5035 3060);
FORCEPROP 2 LASTPIN (-5025 3100) $PN DD49
J 2
(-5035 3110);
DISPLAY 0.617021 (-5035 3110);
PAINT ORANGE (-5035 3110);
FORCEPROP 2 LASTPIN (-5025 3850) $PN DV63
J 2
(-5035 3860);
DISPLAY 0.617021 (-5035 3860);
PAINT ORANGE (-5035 3860);
FORCEPROP 2 LASTPIN (-5025 3750) $PN AH13
J 2
(-5035 3760);
DISPLAY 0.617021 (-5035 3760);
PAINT ORANGE (-5035 3760);
FORCEPROP 2 LASTPIN (-5025 3700) $PN AF13
J 2
(-5035 3710);
DISPLAY 0.617021 (-5035 3710);
PAINT ORANGE (-5035 3710);
FORCEPROP 2 LASTPIN (-5025 2350) $PN CR30
J 2
(-5035 2360);
DISPLAY 0.617021 (-5035 2360);
PAINT ORANGE (-5035 2360);
FORCEPROP 2 LASTPIN (-5025 2200) $PN CN30
J 2
(-5035 2210);
DISPLAY 0.617021 (-5035 2210);
PAINT ORANGE (-5035 2210);
FORCEPROP 2 LASTPIN (-5025 2600) $PN AL18
J 2
(-5035 2610);
DISPLAY 0.617021 (-5035 2610);
PAINT ORANGE (-5035 2610);
FORCEPROP 2 LASTPIN (-5025 2500) $PN CT59
J 2
(-5035 2510);
DISPLAY 0.617021 (-5035 2510);
PAINT ORANGE (-5035 2510);
FORCEPROP 2 LASTPIN (-5025 2450) $PN CW58
J 2
(-5035 2460);
DISPLAY 0.617021 (-5035 2460);
PAINT ORANGE (-5035 2460);
FORCEPROP 2 LASTPIN (-5025 2100) $PN AT29
J 2
(-5035 2110);
DISPLAY 0.617021 (-5035 2110);
PAINT ORANGE (-5035 2110);
FORCEPROP 2 LASTPIN (-5025 2150) $PN AP29
J 2
(-5035 2160);
DISPLAY 0.617021 (-5035 2160);
PAINT ORANGE (-5035 2160);
FORCEPROP 2 LASTPIN (-5025 2050) $PN CK29
J 2
(-5035 2060);
DISPLAY 0.617021 (-5035 2060);
PAINT ORANGE (-5035 2060);
FORCEPROP 2 LASTPIN (-5025 3600) $PN CV61
J 2
(-5035 3610);
DISPLAY 0.617021 (-5035 3610);
PAINT ORANGE (-5035 3610);
FORCEPROP 2 LASTPIN (-5025 2800) $PN AE18
J 2
(-5035 2810);
DISPLAY 0.617021 (-5035 2810);
PAINT ORANGE (-5035 2810);
FORCEPROP 2 LASTPIN (-5025 2750) $PN AJ18
J 2
(-5035 2760);
DISPLAY 0.617021 (-5035 2760);
PAINT ORANGE (-5035 2760);
FORCEPROP 2 LASTPIN (-5025 2250) $PN CL30
J 2
(-5035 2260);
DISPLAY 0.617021 (-5035 2260);
PAINT ORANGE (-5035 2260);
FORCEPROP 2 LASTPIN (-5025 2300) $PN CP29
J 2
(-5035 2310);
DISPLAY 0.617021 (-5035 2310);
PAINT ORANGE (-5035 2310);
FORCEPROP 1 LAST PART_NUMBER TBD
J 0
(-4975 950);
DISPLAY 0.617021 (-4975 950);
PAINT BLUE (-4975 950);
FORCEPROP 2 LASTPIN (-5025 1200) $PN Y13
J 2
(-5035 1210);
DISPLAY 0.617021 (-5035 1210);
PAINT ORANGE (-5035 1210);
FORCEPROP 2 LASTPIN (-5025 1500) $PN AH11
J 2
(-5035 1510);
DISPLAY 0.617021 (-5035 1510);
PAINT ORANGE (-5035 1510);
FORCEPROP 2 LASTPIN (-5025 1550) $PN AG10
J 2
(-5035 1560);
DISPLAY 0.617021 (-5035 1560);
PAINT ORANGE (-5035 1560);
FORCEPROP 2 LASTPIN (-5025 1600) $PN AF11
J 2
(-5035 1610);
DISPLAY 0.617021 (-5035 1610);
PAINT ORANGE (-5035 1610);
FORCEPROP 2 LASTPIN (-5025 1650) $PN AA12
J 2
(-5035 1660);
DISPLAY 0.617021 (-5035 1660);
PAINT ORANGE (-5035 1660);
FORCEPROP 2 LASTPIN (-5025 1700) $PN Y11
J 2
(-5035 1710);
DISPLAY 0.617021 (-5035 1710);
PAINT ORANGE (-5035 1710);
FORCEPROP 2 LASTPIN (-5025 1800) $PN AC12
J 2
(-5035 1810);
DISPLAY 0.617021 (-5035 1810);
PAINT ORANGE (-5035 1810);
FORCEPROP 2 LASTPIN (-5025 1950) $PN CT31
J 2
(-5035 1960);
DISPLAY 0.617021 (-5035 1960);
PAINT ORANGE (-5035 1960);
FORCEPROP 2 LASTPIN (-5025 1300) $PN AA14
J 2
(-5035 1310);
DISPLAY 0.617021 (-5035 1310);
PAINT ORANGE (-5035 1310);
FORCEPROP 2 LASTPIN (-5025 1350) $PN AC14
J 2
(-5035 1360);
DISPLAY 0.617021 (-5035 1360);
PAINT ORANGE (-5035 1360);
FORCEPROP 2 LASTPIN (-5025 1250) $PN W14
J 2
(-5035 1260);
DISPLAY 0.617021 (-5035 1260);
PAINT ORANGE (-5035 1260);
FORCEPROP 2 LASTPIN (-5025 2000) $PN CL28
J 2
(-5035 2010);
DISPLAY 0.617021 (-5035 2010);
PAINT ORANGE (-5035 2010);
FORCEPROP 2 LASTPIN (-5025 1450) $PN AJ10
J 2
(-5035 1460);
DISPLAY 0.617021 (-5035 1460);
PAINT ORANGE (-5035 1460);
FORCEPROP 2 LASTPIN (-5025 1750) $PN AE12
J 2
(-5035 1760);
DISPLAY 0.617021 (-5035 1760);
PAINT ORANGE (-5035 1760);
FORCEPROP 2 LASTPIN (-5025 1900) $PN CU32
J 2
(-5035 1910);
DISPLAY 0.617021 (-5035 1910);
PAINT ORANGE (-5035 1910);
FORCEPROP 2 LASTPIN (-5025 3200) $PN AB43
J 2
(-5035 3210);
DISPLAY 0.617021 (-5035 3210);
PAINT ORANGE (-5035 3210);
FORCEPROP 2 LASTPIN (-3125 1500) $PN AY19
J 0
(-3115 1510);
DISPLAY 0.617021 (-3115 1510);
PAINT ORANGE (-3115 1510);
FORCEPROP 2 LASTPIN (-5025 2900) $PN AD17
J 2
(-5035 2910);
DISPLAY 0.617021 (-5035 2910);
PAINT ORANGE (-5035 2910);
FORCEPROP 2 LASTPIN (-3125 3900) $PN DL44
J 0
(-3115 3910);
DISPLAY 0.617021 (-3115 3910);
PAINT ORANGE (-3115 3910);
FORCEPROP 2 LASTPIN (-5025 3900) $PN U64
J 2
(-5035 3910);
DISPLAY 0.617021 (-5035 3910);
PAINT ORANGE (-5035 3910);
FORCEPROP 1 LAST PATH I259
J 0
(-4075 4700);
PAINT GREEN (-4075 4700);
DISPLAY INVISIBLE (-4075 4700);
FORCEPROP 2 LAST CDS_LIB chpset_lib
J 0
(-4075 2850);
PAINT ORANGE (-4075 2850);
DISPLAY INVISIBLE (-4075 2850);
FORCEPROP 2 LAST SEC_TYPE BGA1
J 0
(-4975 4800);
DISPLAY 1.021277 (-4975 4800);
PAINT ORANGE (-4975 4800);
DISPLAY INVISIBLE (-4975 4800);
FORCEPROP 2 LAST SEC 1
J 0
(-4975 4800);
DISPLAY 0.680851 (-4975 4800);
PAINT MONO (-4975 4800);
DISPLAY INVISIBLE (-4975 4800);
FORCEPROP 2 LAST CDS_LOCATION U5D1
J 0
(-4975 4750);
DISPLAY 0.617021 (-4975 4750);
PAINT AQUA (-4975 4750);
DISPLAY INVISIBLE (-4975 4750);
FORCEPROP 1 LAST PACK_TYPE BGA1
J 0
(-4975 4800);
PAINT SKYBLUE (-4975 4800);
DISPLAY INVISIBLE (-4975 4800);
FORCEPROP 0 LAST ROOM CPU0
J 0
(-4975 4850);
DISPLAY 1.021277 (-4975 4850);
PAINT ORANGE (-4975 4850);
DISPLAY INVISIBLE (-4975 4850);
FORCEADD OFFPAGE..3
R 2
(-6375 1750);
FORCEPROP 2 LAST $XR1 112 
J 0
(-6744 1750);
DISPLAY 0.638298 (-6744 1750);
PAINT MONO (-6744 1750);
FORCEPROP 2 LAST $XR0 55 
J 0
(-6624 1750);
DISPLAY 0.638298 (-6624 1750);
PAINT MONO (-6624 1750);
FORCEPROP 2 LAST PATH I260
J 0
(-6325 1825);
DISPLAY 1.021277 (-6325 1825);
PAINT ORANGE (-6325 1825);
DISPLAY INVISIBLE (-6325 1825);
FORCEPROP 2 LAST CDS_LIB mstr_standard
J 0
(-6375 1750);
PAINT ORANGE (-6375 1750);
DISPLAY INVISIBLE (-6375 1750);
FORCEPROP 1 LAST OFFPAGE TRUE
J 2
(-6700 1625);
DISPLAY 0.872340 (-6700 1625);
PAINT GREEN (-6700 1625);
DISPLAY INVISIBLE (-6700 1625);
FORCEPROP 1 LAST COMMENT_BODY TRUE
J 2
(-6325 1650);
DISPLAY 0.872340 (-6325 1650);
PAINT GREEN (-6325 1650);
DISPLAY INVISIBLE (-6325 1650);
FORCEADD OFFPAGE..1
R 2
(-1800 1400);
FORCEPROP 2 LAST $XR1 55 
J 0
(-1494 1400);
DISPLAY 0.638298 (-1494 1400);
PAINT MONO (-1494 1400);
FORCEPROP 2 LAST $XR0 112 
J 0
(-1614 1400);
DISPLAY 0.638298 (-1614 1400);
PAINT MONO (-1614 1400);
FORCEPROP 2 LAST PATH I261
J 0
(-1625 1475);
DISPLAY 1.021277 (-1625 1475);
PAINT ORANGE (-1625 1475);
DISPLAY INVISIBLE (-1625 1475);
FORCEPROP 2 LAST CDS_LIB mstr_standard
J 0
(-1800 1400);
PAINT ORANGE (-1800 1400);
DISPLAY INVISIBLE (-1800 1400);
FORCEPROP 1 LAST OFFPAGE TRUE
J 2
(-2125 1275);
DISPLAY 0.872340 (-2125 1275);
PAINT GREEN (-2125 1275);
DISPLAY INVISIBLE (-2125 1275);
FORCEPROP 1 LAST COMMENT_BODY TRUE
J 2
(-1925 1300);
DISPLAY 0.872340 (-1925 1300);
PAINT GREEN (-1925 1300);
DISPLAY INVISIBLE (-1925 1300);
FORCEADD OFFPAGE..2
(-1800 1350);
FORCEPROP 2 LAST $XR1 112 
J 0
(-1521 1350);
DISPLAY 0.638298 (-1521 1350);
PAINT MONO (-1521 1350);
FORCEPROP 2 LAST $XR0 55 
J 0
(-1611 1350);
DISPLAY 0.638298 (-1611 1350);
PAINT MONO (-1611 1350);
FORCEPROP 2 LAST PATH I262
J 0
(-1625 1425);
DISPLAY 1.021277 (-1625 1425);
PAINT ORANGE (-1625 1425);
DISPLAY INVISIBLE (-1625 1425);
FORCEPROP 2 LAST CDS_LIB mstr_standard
J 0
(-1800 1350);
PAINT ORANGE (-1800 1350);
DISPLAY INVISIBLE (-1800 1350);
FORCEPROP 1 LAST OFFPAGE TRUE
J 0
(-1475 1225);
DISPLAY 1.170213 (-1475 1225);
PAINT GREEN (-1475 1225);
DISPLAY INVISIBLE (-1475 1225);
FORCEPROP 1 LAST COMMENT_BODY TRUE
J 0
(-1845 1255);
DISPLAY 1.170213 (-1845 1255);
PAINT PEACH (-1845 1255);
DISPLAY INVISIBLE (-1845 1255);
FORCEADD OFFPAGE..1
(-6325 2500);
FORCEPROP 2 LAST $XR0 156 
J 0
(-6607 2500);
DISPLAY 0.638298 (-6607 2500);
PAINT MONO (-6607 2500);
FORCEPROP 2 LAST PATH I263
J 0
(-6275 2575);
DISPLAY 1.021277 (-6275 2575);
PAINT ORANGE (-6275 2575);
DISPLAY INVISIBLE (-6275 2575);
FORCEPROP 2 LAST CDS_LIB mstr_standard
J 0
(-6325 2500);
PAINT ORANGE (-6325 2500);
DISPLAY INVISIBLE (-6325 2500);
FORCEPROP 1 LAST OFFPAGE TRUE
J 0
(-6000 2375);
DISPLAY 0.872340 (-6000 2375);
PAINT GREEN (-6000 2375);
DISPLAY INVISIBLE (-6000 2375);
FORCEPROP 1 LAST COMMENT_BODY TRUE
J 0
(-6200 2400);
DISPLAY 0.872340 (-6200 2400);
PAINT GREEN (-6200 2400);
DISPLAY INVISIBLE (-6200 2400);
FORCEADD OFFPAGE..6
(-6325 2450);
FORCEPROP 2 LAST $XR0 156 
J 0
(-6605 2450);
DISPLAY 0.638298 (-6605 2450);
PAINT MONO (-6605 2450);
FORCEPROP 2 LAST PATH I264
J 0
(-6275 2525);
DISPLAY 1.021277 (-6275 2525);
PAINT ORANGE (-6275 2525);
DISPLAY INVISIBLE (-6275 2525);
FORCEPROP 2 LAST CDS_LIB mstr_standard
J 0
(-6325 2450);
PAINT ORANGE (-6325 2450);
DISPLAY INVISIBLE (-6325 2450);
FORCEPROP 1 LAST OFFPAGE TRUE
J 0
(-6000 2325);
DISPLAY 0.872340 (-6000 2325);
PAINT GREEN (-6000 2325);
DISPLAY INVISIBLE (-6000 2325);
FORCEPROP 1 LAST COMMENT_BODY TRUE
J 0
(-6225 2375);
DISPLAY 0.872340 (-6225 2375);
PAINT GREEN (-6225 2375);
DISPLAY INVISIBLE (-6225 2375);
FORCEADD OFFPAGE..4
(-1800 2050);
FORCEPROP 2 LAST $XR0 156 
J 0
(-1614 2050);
DISPLAY 0.638298 (-1614 2050);
PAINT MONO (-1614 2050);
FORCEPROP 2 LAST PATH I265
J 0
(-1750 2125);
DISPLAY 1.021277 (-1750 2125);
PAINT ORANGE (-1750 2125);
DISPLAY INVISIBLE (-1750 2125);
FORCEPROP 2 LAST CDS_LIB mstr_standard
J 0
(-1800 2050);
PAINT ORANGE (-1800 2050);
DISPLAY INVISIBLE (-1800 2050);
FORCEPROP 1 LAST OFFPAGE TRUE
J 0
(-1475 1925);
DISPLAY 0.872340 (-1475 1925);
PAINT GREEN (-1475 1925);
DISPLAY INVISIBLE (-1475 1925);
FORCEPROP 1 LAST COMMENT_BODY TRUE
J 0
(-1825 1950);
DISPLAY 0.872340 (-1825 1950);
PAINT GREEN (-1825 1950);
DISPLAY INVISIBLE (-1825 1950);
FORCEADD OFFPAGE..4
(-1800 1800);
FORCEPROP 2 LAST $XR0 156 
J 0
(-1614 1800);
DISPLAY 0.638298 (-1614 1800);
PAINT MONO (-1614 1800);
FORCEPROP 2 LAST PATH I266
J 0
(-1625 1875);
DISPLAY 1.021277 (-1625 1875);
PAINT ORANGE (-1625 1875);
DISPLAY INVISIBLE (-1625 1875);
FORCEPROP 2 LAST CDS_LIB mstr_standard
J 0
(-1800 1800);
PAINT ORANGE (-1800 1800);
DISPLAY INVISIBLE (-1800 1800);
FORCEPROP 1 LAST OFFPAGE TRUE
J 0
(-1475 1675);
DISPLAY 0.872340 (-1475 1675);
PAINT GREEN (-1475 1675);
DISPLAY INVISIBLE (-1475 1675);
FORCEPROP 1 LAST COMMENT_BODY TRUE
J 0
(-1825 1700);
DISPLAY 0.872340 (-1825 1700);
PAINT GREEN (-1825 1700);
DISPLAY INVISIBLE (-1825 1700);
FORCEADD OFFPAGE..4
(-1800 1750);
FORCEPROP 2 LAST $XR0 156 
J 0
(-1614 1750);
DISPLAY 0.638298 (-1614 1750);
PAINT MONO (-1614 1750);
FORCEPROP 2 LAST PATH I267
J 0
(-1625 1825);
DISPLAY 1.021277 (-1625 1825);
PAINT ORANGE (-1625 1825);
DISPLAY INVISIBLE (-1625 1825);
FORCEPROP 2 LAST CDS_LIB mstr_standard
J 0
(-1800 1750);
PAINT ORANGE (-1800 1750);
DISPLAY INVISIBLE (-1800 1750);
FORCEPROP 1 LAST OFFPAGE TRUE
J 0
(-1475 1625);
DISPLAY 0.872340 (-1475 1625);
PAINT GREEN (-1475 1625);
DISPLAY INVISIBLE (-1475 1625);
FORCEPROP 1 LAST COMMENT_BODY TRUE
J 0
(-1825 1650);
DISPLAY 0.872340 (-1825 1650);
PAINT GREEN (-1825 1650);
DISPLAY INVISIBLE (-1825 1650);
FORCEADD OFFPAGE..4
(-1800 1700);
FORCEPROP 2 LAST $XR0 156 
J 0
(-1614 1700);
DISPLAY 0.638298 (-1614 1700);
PAINT MONO (-1614 1700);
FORCEPROP 2 LAST PATH I268
J 0
(-1625 1775);
DISPLAY 1.021277 (-1625 1775);
PAINT ORANGE (-1625 1775);
DISPLAY INVISIBLE (-1625 1775);
FORCEPROP 2 LAST CDS_LIB mstr_standard
J 0
(-1800 1700);
PAINT ORANGE (-1800 1700);
DISPLAY INVISIBLE (-1800 1700);
FORCEPROP 1 LAST OFFPAGE TRUE
J 0
(-1475 1575);
DISPLAY 0.872340 (-1475 1575);
PAINT GREEN (-1475 1575);
DISPLAY INVISIBLE (-1475 1575);
FORCEPROP 1 LAST COMMENT_BODY TRUE
J 0
(-1825 1600);
DISPLAY 0.872340 (-1825 1600);
PAINT GREEN (-1825 1600);
DISPLAY INVISIBLE (-1825 1600);
FORCEADD OFFPAGE..6
(-6325 2600);
FORCEPROP 2 LAST $XR0 248 
J 0
(-6605 2600);
DISPLAY 0.638298 (-6605 2600);
PAINT MONO (-6605 2600);
FORCEPROP 2 LAST PATH I270
J 0
(-6275 2675);
DISPLAY 1.021277 (-6275 2675);
PAINT ORANGE (-6275 2675);
DISPLAY INVISIBLE (-6275 2675);
FORCEPROP 2 LAST CDS_LIB mstr_standard
J 0
(-6325 2600);
PAINT ORANGE (-6325 2600);
DISPLAY INVISIBLE (-6325 2600);
FORCEPROP 1 LAST OFFPAGE TRUE
J 0
(-6000 2475);
DISPLAY 0.872340 (-6000 2475);
PAINT GREEN (-6000 2475);
DISPLAY INVISIBLE (-6000 2475);
FORCEPROP 1 LAST COMMENT_BODY TRUE
J 0
(-6225 2525);
DISPLAY 0.872340 (-6225 2525);
PAINT GREEN (-6225 2525);
DISPLAY INVISIBLE (-6225 2525);
FORCEADD OFFPAGE..5
(-6350 2650);
FORCEPROP 2 LAST $XR0 248 
J 0
(-6605 2650);
DISPLAY 0.638298 (-6605 2650);
PAINT MONO (-6605 2650);
FORCEPROP 2 LAST PATH I271
J 0
(-6300 2725);
DISPLAY 1.021277 (-6300 2725);
PAINT ORANGE (-6300 2725);
DISPLAY INVISIBLE (-6300 2725);
FORCEPROP 2 LAST CDS_LIB mstr_standard
J 0
(-6350 2650);
PAINT MONO (-6350 2650);
DISPLAY INVISIBLE (-6350 2650);
FORCEPROP 1 LAST OFFPAGE TRUE
J 0
(-6025 2525);
DISPLAY 1.170213 (-6025 2525);
PAINT GREEN (-6025 2525);
DISPLAY INVISIBLE (-6025 2525);
FORCEPROP 1 LAST COMMENT_BODY TRUE
J 0
(-6250 2575);
DISPLAY 1.170213 (-6250 2575);
PAINT PEACH (-6250 2575);
DISPLAY INVISIBLE (-6250 2575);
FORCEADD OFFPAGE..1
(-6350 4450);
FORCEPROP 2 LAST $XR0 103 
J 0
(-6602 4450);
DISPLAY 0.638298 (-6602 4450);
PAINT MONO (-6602 4450);
FORCEPROP 2 LAST PATH I4
J 0
(-6300 4525);
DISPLAY 1.361702 (-6300 4525);
PAINT ORANGE (-6300 4525);
DISPLAY INVISIBLE (-6300 4525);
FORCEPROP 2 LAST CDS_LIB mstr_standard
J 0
(-6350 4450);
PAINT MONO (-6350 4450);
DISPLAY INVISIBLE (-6350 4450);
FORCEPROP 1 LAST OFFPAGE TRUE
J 0
(-6025 4325);
DISPLAY 1.170213 (-6025 4325);
PAINT GREEN (-6025 4325);
DISPLAY INVISIBLE (-6025 4325);
FORCEPROP 1 LAST COMMENT_BODY TRUE
J 0
(-6225 4350);
DISPLAY 1.170213 (-6225 4350);
PAINT PEACH (-6225 4350);
DISPLAY INVISIBLE (-6225 4350);
FORCEADD OFFPAGE..6
(-6375 1500);
FORCEPROP 2 LAST $XR1 112 
J 0
(-6744 1500);
DISPLAY 0.638298 (-6744 1500);
PAINT MONO (-6744 1500);
FORCEPROP 2 LAST $XR0 55 
J 0
(-6624 1500);
DISPLAY 0.638298 (-6624 1500);
PAINT MONO (-6624 1500);
FORCEPROP 2 LAST PATH I43
J 0
(-6325 1575);
DISPLAY 1.361702 (-6325 1575);
PAINT ORANGE (-6325 1575);
DISPLAY INVISIBLE (-6325 1575);
FORCEPROP 2 LAST CDS_LIB mstr_standard
J 0
(-6375 1500);
PAINT MONO (-6375 1500);
DISPLAY INVISIBLE (-6375 1500);
FORCEPROP 1 LAST OFFPAGE TRUE
J 0
(-6050 1375);
DISPLAY 1.170213 (-6050 1375);
PAINT GREEN (-6050 1375);
DISPLAY INVISIBLE (-6050 1375);
FORCEPROP 1 LAST COMMENT_BODY TRUE
J 0
(-6275 1425);
DISPLAY 1.170213 (-6275 1425);
PAINT PEACH (-6275 1425);
DISPLAY INVISIBLE (-6275 1425);
FORCEADD OFFPAGE..6
(-6375 1450);
FORCEPROP 2 LAST PATH I44
J 0
(-6325 1525);
DISPLAY 1.361702 (-6325 1525);
PAINT ORANGE (-6325 1525);
DISPLAY INVISIBLE (-6325 1525);
FORCEPROP 2 LAST CDS_LIB mstr_standard
J 0
(-6375 1450);
PAINT MONO (-6375 1450);
DISPLAY INVISIBLE (-6375 1450);
FORCEPROP 1 LAST OFFPAGE TRUE
J 0
(-6050 1325);
DISPLAY 1.170213 (-6050 1325);
PAINT GREEN (-6050 1325);
DISPLAY INVISIBLE (-6050 1325);
FORCEPROP 1 LAST COMMENT_BODY TRUE
J 0
(-6275 1375);
DISPLAY 1.170213 (-6275 1375);
PAINT PEACH (-6275 1375);
DISPLAY INVISIBLE (-6275 1375);
FORCEPROP 2 LAST $XR1 112 
J 0
(-6829 1450);
DISPLAY 0.638298 (-6829 1450);
PAINT MONO (-6829 1450);
DISPLAY INVISIBLE (-6829 1450);
FORCEPROP 2 LAST $XR0 55 
J 0
(-6829 1450);
DISPLAY 0.638298 (-6829 1450);
PAINT MONO (-6829 1450);
DISPLAY INVISIBLE (-6829 1450);
FORCEADD OFFPAGE..1
(-6375 1350);
FORCEPROP 2 LAST $XR0 112 
J 0
(-6627 1350);
DISPLAY 0.638298 (-6627 1350);
PAINT MONO (-6627 1350);
FORCEPROP 2 LAST PATH I47
J 0
(-6325 1425);
DISPLAY 1.361702 (-6325 1425);
PAINT ORANGE (-6325 1425);
DISPLAY INVISIBLE (-6325 1425);
FORCEPROP 2 LAST CDS_LIB mstr_standard
J 0
(-6375 1350);
PAINT MONO (-6375 1350);
DISPLAY INVISIBLE (-6375 1350);
FORCEPROP 1 LAST OFFPAGE TRUE
J 0
(-6050 1225);
DISPLAY 1.170213 (-6050 1225);
PAINT GREEN (-6050 1225);
DISPLAY INVISIBLE (-6050 1225);
FORCEPROP 1 LAST COMMENT_BODY TRUE
J 0
(-6250 1250);
DISPLAY 1.170213 (-6250 1250);
PAINT PEACH (-6250 1250);
DISPLAY INVISIBLE (-6250 1250);
FORCEADD OFFPAGE..1
(-6375 1300);
FORCEPROP 2 LAST $XR3 112 
J 0
(-6957 1300);
DISPLAY 0.638298 (-6957 1300);
PAINT MONO (-6957 1300);
FORCEPROP 2 LAST $XR2 55 
J 0
(-6837 1300);
DISPLAY 0.638298 (-6837 1300);
PAINT MONO (-6837 1300);
FORCEPROP 2 LAST $XR1 254 
J 0
(-6747 1300);
DISPLAY 0.638298 (-6747 1300);
PAINT MONO (-6747 1300);
FORCEPROP 2 LAST $XR0 111 
J 0
(-6627 1300);
DISPLAY 0.638298 (-6627 1300);
PAINT MONO (-6627 1300);
FORCEPROP 2 LAST PATH I48
J 0
(-6325 1375);
DISPLAY 1.361702 (-6325 1375);
PAINT ORANGE (-6325 1375);
DISPLAY INVISIBLE (-6325 1375);
FORCEPROP 2 LAST CDS_LIB mstr_standard
J 0
(-6375 1300);
PAINT MONO (-6375 1300);
DISPLAY INVISIBLE (-6375 1300);
FORCEPROP 1 LAST OFFPAGE TRUE
J 0
(-6050 1175);
DISPLAY 1.170213 (-6050 1175);
PAINT GREEN (-6050 1175);
DISPLAY INVISIBLE (-6050 1175);
FORCEPROP 1 LAST COMMENT_BODY TRUE
J 0
(-6250 1200);
DISPLAY 1.170213 (-6250 1200);
PAINT PEACH (-6250 1200);
DISPLAY INVISIBLE (-6250 1200);
FORCEADD OFFPAGE..1
(-6375 1250);
FORCEPROP 2 LAST $XR1 55 
J 0
(-6717 1250);
DISPLAY 0.638298 (-6717 1250);
PAINT MONO (-6717 1250);
FORCEPROP 2 LAST $XR0 112 
J 0
(-6627 1250);
DISPLAY 0.638298 (-6627 1250);
PAINT MONO (-6627 1250);
FORCEPROP 2 LAST PATH I49
J 0
(-6325 1325);
DISPLAY 1.361702 (-6325 1325);
PAINT ORANGE (-6325 1325);
DISPLAY INVISIBLE (-6325 1325);
FORCEPROP 2 LAST CDS_LIB mstr_standard
J 0
(-6375 1250);
PAINT MONO (-6375 1250);
DISPLAY INVISIBLE (-6375 1250);
FORCEPROP 1 LAST OFFPAGE TRUE
J 0
(-6050 1125);
DISPLAY 1.170213 (-6050 1125);
PAINT GREEN (-6050 1125);
DISPLAY INVISIBLE (-6050 1125);
FORCEPROP 1 LAST COMMENT_BODY TRUE
J 0
(-6250 1150);
DISPLAY 1.170213 (-6250 1150);
PAINT PEACH (-6250 1150);
DISPLAY INVISIBLE (-6250 1150);
FORCEADD OFFPAGE..1
(-6350 4350);
FORCEPROP 2 LAST $XR0 103 
J 0
(-6602 4350);
DISPLAY 0.638298 (-6602 4350);
PAINT MONO (-6602 4350);
FORCEPROP 2 LAST PATH I5
J 0
(-6300 4425);
DISPLAY 1.361702 (-6300 4425);
PAINT ORANGE (-6300 4425);
DISPLAY INVISIBLE (-6300 4425);
FORCEPROP 2 LAST CDS_LIB mstr_standard
J 0
(-6350 4350);
PAINT MONO (-6350 4350);
DISPLAY INVISIBLE (-6350 4350);
FORCEPROP 1 LAST OFFPAGE TRUE
J 0
(-6025 4225);
DISPLAY 1.170213 (-6025 4225);
PAINT GREEN (-6025 4225);
DISPLAY INVISIBLE (-6025 4225);
FORCEPROP 1 LAST COMMENT_BODY TRUE
J 0
(-6225 4250);
DISPLAY 1.170213 (-6225 4250);
PAINT PEACH (-6225 4250);
DISPLAY INVISIBLE (-6225 4250);
FORCEADD OFFPAGE..1
(-6375 1200);
FORCEPROP 2 LAST $XR1 55 
J 0
(-6717 1200);
DISPLAY 0.638298 (-6717 1200);
PAINT MONO (-6717 1200);
FORCEPROP 2 LAST $XR0 112 
J 0
(-6627 1200);
DISPLAY 0.638298 (-6627 1200);
PAINT MONO (-6627 1200);
FORCEPROP 2 LAST PATH I50
J 0
(-6325 1275);
DISPLAY 1.361702 (-6325 1275);
PAINT ORANGE (-6325 1275);
DISPLAY INVISIBLE (-6325 1275);
FORCEPROP 2 LAST CDS_LIB mstr_standard
J 0
(-6375 1200);
PAINT MONO (-6375 1200);
DISPLAY INVISIBLE (-6375 1200);
FORCEPROP 1 LAST OFFPAGE TRUE
J 0
(-6050 1075);
DISPLAY 1.170213 (-6050 1075);
PAINT GREEN (-6050 1075);
DISPLAY INVISIBLE (-6050 1075);
FORCEPROP 1 LAST COMMENT_BODY TRUE
J 0
(-6250 1100);
DISPLAY 1.170213 (-6250 1100);
PAINT PEACH (-6250 1100);
DISPLAY INVISIBLE (-6250 1100);
FORCEADD OFFPAGE..1
(-6350 4300);
FORCEPROP 2 LAST $XR0 103 
J 0
(-6602 4300);
DISPLAY 0.638298 (-6602 4300);
PAINT MONO (-6602 4300);
FORCEPROP 2 LAST PATH I6
J 0
(-6300 4375);
DISPLAY 1.361702 (-6300 4375);
PAINT ORANGE (-6300 4375);
DISPLAY INVISIBLE (-6300 4375);
FORCEPROP 2 LAST CDS_LIB mstr_standard
J 0
(-6350 4300);
PAINT MONO (-6350 4300);
DISPLAY INVISIBLE (-6350 4300);
FORCEPROP 1 LAST OFFPAGE TRUE
J 0
(-6025 4175);
DISPLAY 1.170213 (-6025 4175);
PAINT GREEN (-6025 4175);
DISPLAY INVISIBLE (-6025 4175);
FORCEPROP 1 LAST COMMENT_BODY TRUE
J 0
(-6225 4200);
DISPLAY 1.170213 (-6225 4200);
PAINT PEACH (-6225 4200);
DISPLAY INVISIBLE (-6225 4200);
FORCEADD OFFPAGE..3
(-1825 3650);
FORCEPROP 2 LAST $XR0 92 
J 0
(-1611 3650);
DISPLAY 0.638298 (-1611 3650);
PAINT MONO (-1611 3650);
FORCEPROP 2 LAST PATH I66
J 0
(-1650 3725);
DISPLAY 1.361702 (-1650 3725);
PAINT ORANGE (-1650 3725);
DISPLAY INVISIBLE (-1650 3725);
FORCEPROP 2 LAST CDS_LIB mstr_standard
J 0
(-1825 3650);
PAINT MONO (-1825 3650);
DISPLAY INVISIBLE (-1825 3650);
FORCEPROP 1 LAST OFFPAGE TRUE
J 0
(-1500 3525);
DISPLAY 0.872340 (-1500 3525);
PAINT GREEN (-1500 3525);
DISPLAY INVISIBLE (-1500 3525);
FORCEPROP 1 LAST COMMENT_BODY TRUE
J 0
(-1875 3550);
DISPLAY 0.872340 (-1875 3550);
PAINT GREEN (-1875 3550);
DISPLAY INVISIBLE (-1875 3550);
FORCEADD OFFPAGE..2
(-1800 3550);
FORCEPROP 2 LAST $XR0 92 
J 0
(-1611 3550);
DISPLAY 0.638298 (-1611 3550);
PAINT MONO (-1611 3550);
FORCEPROP 2 LAST PATH I67
J 0
(-1625 3625);
DISPLAY 1.361702 (-1625 3625);
PAINT ORANGE (-1625 3625);
DISPLAY INVISIBLE (-1625 3625);
FORCEPROP 2 LAST CDS_LIB mstr_standard
J 0
(-1800 3550);
PAINT MONO (-1800 3550);
DISPLAY INVISIBLE (-1800 3550);
FORCEPROP 1 LAST OFFPAGE TRUE
J 0
(-1475 3425);
DISPLAY 0.872340 (-1475 3425);
PAINT GREEN (-1475 3425);
DISPLAY INVISIBLE (-1475 3425);
FORCEPROP 1 LAST COMMENT_BODY TRUE
J 0
(-1845 3455);
DISPLAY 0.872340 (-1845 3455);
PAINT GREEN (-1845 3455);
DISPLAY INVISIBLE (-1845 3455);
FORCEADD OFFPAGE..2
(-1800 3500);
FORCEPROP 2 LAST $XR0 93 
J 0
(-1611 3500);
DISPLAY 0.638298 (-1611 3500);
PAINT MONO (-1611 3500);
FORCEPROP 2 LAST PATH I68
J 0
(-1625 3575);
DISPLAY 1.361702 (-1625 3575);
PAINT ORANGE (-1625 3575);
DISPLAY INVISIBLE (-1625 3575);
FORCEPROP 2 LAST CDS_LIB mstr_standard
J 0
(-1800 3500);
PAINT MONO (-1800 3500);
DISPLAY INVISIBLE (-1800 3500);
FORCEPROP 1 LAST OFFPAGE TRUE
J 0
(-1475 3375);
DISPLAY 0.872340 (-1475 3375);
PAINT GREEN (-1475 3375);
DISPLAY INVISIBLE (-1475 3375);
FORCEPROP 1 LAST COMMENT_BODY TRUE
J 0
(-1845 3405);
DISPLAY 0.872340 (-1845 3405);
PAINT GREEN (-1845 3405);
DISPLAY INVISIBLE (-1845 3405);
FORCEADD OFFPAGE..2
(-1800 3450);
FORCEPROP 2 LAST $XR0 93 
J 0
(-1611 3450);
DISPLAY 0.638298 (-1611 3450);
PAINT MONO (-1611 3450);
FORCEPROP 2 LAST PATH I69
J 0
(-1625 3525);
DISPLAY 1.361702 (-1625 3525);
PAINT ORANGE (-1625 3525);
DISPLAY INVISIBLE (-1625 3525);
FORCEPROP 2 LAST CDS_LIB mstr_standard
J 0
(-1800 3450);
PAINT MONO (-1800 3450);
DISPLAY INVISIBLE (-1800 3450);
FORCEPROP 1 LAST OFFPAGE TRUE
J 0
(-1475 3325);
DISPLAY 0.872340 (-1475 3325);
PAINT GREEN (-1475 3325);
DISPLAY INVISIBLE (-1475 3325);
FORCEPROP 1 LAST COMMENT_BODY TRUE
J 0
(-1845 3355);
DISPLAY 0.872340 (-1845 3355);
PAINT GREEN (-1845 3355);
DISPLAY INVISIBLE (-1845 3355);
FORCEADD OFFPAGE..1
(-6350 4050);
FORCEPROP 2 LAST $XR0 96 
J 0
(-6601 4050);
DISPLAY 0.638298 (-6601 4050);
PAINT MONO (-6601 4050);
FORCEPROP 2 LAST PATH I7
J 0
(-6300 4125);
DISPLAY 1.361702 (-6300 4125);
PAINT ORANGE (-6300 4125);
DISPLAY INVISIBLE (-6300 4125);
FORCEPROP 2 LAST CDS_LIB mstr_standard
J 0
(-6350 4050);
PAINT MONO (-6350 4050);
DISPLAY INVISIBLE (-6350 4050);
FORCEPROP 1 LAST OFFPAGE TRUE
J 0
(-6025 3925);
DISPLAY 1.170213 (-6025 3925);
PAINT GREEN (-6025 3925);
DISPLAY INVISIBLE (-6025 3925);
FORCEPROP 1 LAST COMMENT_BODY TRUE
J 0
(-6225 3950);
DISPLAY 1.170213 (-6225 3950);
PAINT PEACH (-6225 3950);
DISPLAY INVISIBLE (-6225 3950);
FORCEADD OFFPAGE..3
(-1825 3200);
FORCEPROP 2 LAST $XR1 93 
J 0
(-1521 3200);
DISPLAY 0.638298 (-1521 3200);
PAINT MONO (-1521 3200);
FORCEPROP 2 LAST $XR0 95 
J 0
(-1611 3200);
DISPLAY 0.638298 (-1611 3200);
PAINT MONO (-1611 3200);
FORCEPROP 2 LAST PATH I71
J 0
(-1650 3275);
DISPLAY 1.361702 (-1650 3275);
PAINT ORANGE (-1650 3275);
DISPLAY INVISIBLE (-1650 3275);
FORCEPROP 2 LAST CDS_LIB mstr_standard
J 0
(-1825 3200);
PAINT MONO (-1825 3200);
DISPLAY INVISIBLE (-1825 3200);
FORCEPROP 1 LAST OFFPAGE TRUE
J 0
(-1500 3075);
DISPLAY 1.170213 (-1500 3075);
PAINT GREEN (-1500 3075);
DISPLAY INVISIBLE (-1500 3075);
FORCEPROP 1 LAST COMMENT_BODY TRUE
J 0
(-1875 3100);
DISPLAY 1.170213 (-1875 3100);
PAINT PEACH (-1875 3100);
DISPLAY INVISIBLE (-1875 3100);
FORCEADD OFFPAGE..2
(-1800 3150);
FORCEPROP 2 LAST $XR0 92 
J 0
(-1611 3150);
DISPLAY 0.638298 (-1611 3150);
PAINT MONO (-1611 3150);
FORCEPROP 2 LAST PATH I72
J 0
(-1625 3225);
DISPLAY 1.361702 (-1625 3225);
PAINT ORANGE (-1625 3225);
DISPLAY INVISIBLE (-1625 3225);
FORCEPROP 2 LAST CDS_LIB mstr_standard
J 0
(-1800 3150);
PAINT MONO (-1800 3150);
DISPLAY INVISIBLE (-1800 3150);
FORCEPROP 1 LAST OFFPAGE TRUE
J 0
(-1475 3025);
DISPLAY 1.170213 (-1475 3025);
PAINT GREEN (-1475 3025);
DISPLAY INVISIBLE (-1475 3025);
FORCEPROP 1 LAST COMMENT_BODY TRUE
J 0
(-1845 3055);
DISPLAY 1.170213 (-1845 3055);
PAINT PEACH (-1845 3055);
DISPLAY INVISIBLE (-1845 3055);
FORCEADD OFFPAGE..4
(-2100 3050);
FORCEPROP 2 LAST $XR0 90 
J 0
(-1914 3050);
DISPLAY 0.638298 (-1914 3050);
PAINT MONO (-1914 3050);
FORCEPROP 2 LAST PATH I74
J 0
(-1925 3125);
DISPLAY 1.361702 (-1925 3125);
PAINT ORANGE (-1925 3125);
DISPLAY INVISIBLE (-1925 3125);
FORCEPROP 2 LAST CDS_LIB mstr_standard
J 0
(-2100 3050);
PAINT MONO (-2100 3050);
DISPLAY INVISIBLE (-2100 3050);
FORCEPROP 1 LAST OFFPAGE TRUE
J 0
(-1775 2925);
DISPLAY 1.170213 (-1775 2925);
PAINT GREEN (-1775 2925);
DISPLAY INVISIBLE (-1775 2925);
FORCEPROP 1 LAST COMMENT_BODY TRUE
J 0
(-2125 2950);
DISPLAY 1.170213 (-2125 2950);
PAINT PEACH (-2125 2950);
DISPLAY INVISIBLE (-2125 2950);
FORCEADD OFFPAGE..4
(-2100 3000);
FORCEPROP 2 LAST $XR0 90 
J 0
(-1914 3000);
DISPLAY 0.638298 (-1914 3000);
PAINT MONO (-1914 3000);
FORCEPROP 2 LAST PATH I75
J 0
(-1925 3075);
DISPLAY 1.361702 (-1925 3075);
PAINT ORANGE (-1925 3075);
DISPLAY INVISIBLE (-1925 3075);
FORCEPROP 2 LAST CDS_LIB mstr_standard
J 0
(-2100 3000);
PAINT MONO (-2100 3000);
DISPLAY INVISIBLE (-2100 3000);
FORCEPROP 1 LAST OFFPAGE TRUE
J 0
(-1775 2875);
DISPLAY 1.170213 (-1775 2875);
PAINT GREEN (-1775 2875);
DISPLAY INVISIBLE (-1775 2875);
FORCEPROP 1 LAST COMMENT_BODY TRUE
J 0
(-2125 2900);
DISPLAY 1.170213 (-2125 2900);
PAINT PEACH (-2125 2900);
DISPLAY INVISIBLE (-2125 2900);
FORCEADD OFFPAGE..4
(-2100 2950);
FORCEPROP 2 LAST $XR1 156 
J 0
(-1824 2950);
DISPLAY 0.638298 (-1824 2950);
PAINT MONO (-1824 2950);
FORCEPROP 2 LAST $XR0 90 
J 0
(-1914 2950);
DISPLAY 0.638298 (-1914 2950);
PAINT MONO (-1914 2950);
FORCEPROP 2 LAST PATH I76
J 0
(-1925 3025);
DISPLAY 1.361702 (-1925 3025);
PAINT ORANGE (-1925 3025);
DISPLAY INVISIBLE (-1925 3025);
FORCEPROP 2 LAST CDS_LIB mstr_standard
J 0
(-2100 2950);
PAINT MONO (-2100 2950);
DISPLAY INVISIBLE (-2100 2950);
FORCEPROP 1 LAST OFFPAGE TRUE
J 0
(-1775 2825);
DISPLAY 1.170213 (-1775 2825);
PAINT GREEN (-1775 2825);
DISPLAY INVISIBLE (-1775 2825);
FORCEPROP 1 LAST COMMENT_BODY TRUE
J 0
(-2125 2850);
DISPLAY 1.170213 (-2125 2850);
PAINT PEACH (-2125 2850);
DISPLAY INVISIBLE (-2125 2850);
FORCEADD OFFPAGE..4
(-2100 2900);
FORCEPROP 2 LAST $XR0 90 
J 0
(-1914 2900);
DISPLAY 0.638298 (-1914 2900);
PAINT MONO (-1914 2900);
FORCEPROP 2 LAST PATH I77
J 0
(-1925 2975);
DISPLAY 1.361702 (-1925 2975);
PAINT ORANGE (-1925 2975);
DISPLAY INVISIBLE (-1925 2975);
FORCEPROP 2 LAST CDS_LIB mstr_standard
J 0
(-2100 2900);
PAINT MONO (-2100 2900);
DISPLAY INVISIBLE (-2100 2900);
FORCEPROP 1 LAST OFFPAGE TRUE
J 0
(-1775 2775);
DISPLAY 1.170213 (-1775 2775);
PAINT GREEN (-1775 2775);
DISPLAY INVISIBLE (-1775 2775);
FORCEPROP 1 LAST COMMENT_BODY TRUE
J 0
(-2125 2800);
DISPLAY 1.170213 (-2125 2800);
PAINT PEACH (-2125 2800);
DISPLAY INVISIBLE (-2125 2800);
FORCEADD OFFPAGE..4
(-2100 2850);
FORCEPROP 2 LAST $XR0 90 
J 0
(-1914 2850);
DISPLAY 0.638298 (-1914 2850);
PAINT MONO (-1914 2850);
FORCEPROP 2 LAST PATH I78
J 0
(-1925 2925);
DISPLAY 1.361702 (-1925 2925);
PAINT ORANGE (-1925 2925);
DISPLAY INVISIBLE (-1925 2925);
FORCEPROP 2 LAST CDS_LIB mstr_standard
J 0
(-2100 2850);
PAINT MONO (-2100 2850);
DISPLAY INVISIBLE (-2100 2850);
FORCEPROP 1 LAST OFFPAGE TRUE
J 0
(-1775 2725);
DISPLAY 1.170213 (-1775 2725);
PAINT GREEN (-1775 2725);
DISPLAY INVISIBLE (-1775 2725);
FORCEPROP 1 LAST COMMENT_BODY TRUE
J 0
(-2125 2750);
DISPLAY 1.170213 (-2125 2750);
PAINT PEACH (-2125 2750);
DISPLAY INVISIBLE (-2125 2750);
FORCEADD OFFPAGE..4
(-2100 2800);
FORCEPROP 2 LAST $XR0 90 
J 0
(-1914 2800);
DISPLAY 0.638298 (-1914 2800);
PAINT MONO (-1914 2800);
FORCEPROP 2 LAST PATH I79
J 0
(-1925 2875);
DISPLAY 1.361702 (-1925 2875);
PAINT ORANGE (-1925 2875);
DISPLAY INVISIBLE (-1925 2875);
FORCEPROP 2 LAST CDS_LIB mstr_standard
J 0
(-2100 2800);
PAINT MONO (-2100 2800);
DISPLAY INVISIBLE (-2100 2800);
FORCEPROP 1 LAST OFFPAGE TRUE
J 0
(-1775 2675);
DISPLAY 1.170213 (-1775 2675);
PAINT GREEN (-1775 2675);
DISPLAY INVISIBLE (-1775 2675);
FORCEPROP 1 LAST COMMENT_BODY TRUE
J 0
(-2125 2700);
DISPLAY 1.170213 (-2125 2700);
PAINT PEACH (-2125 2700);
DISPLAY INVISIBLE (-2125 2700);
FORCEADD OFFPAGE..1
(-6350 4000);
FORCEPROP 2 LAST $XR0 96 
J 0
(-6601 4000);
DISPLAY 0.638298 (-6601 4000);
PAINT MONO (-6601 4000);
FORCEPROP 2 LAST PATH I8
J 0
(-6300 4075);
DISPLAY 1.361702 (-6300 4075);
PAINT ORANGE (-6300 4075);
DISPLAY INVISIBLE (-6300 4075);
FORCEPROP 2 LAST CDS_LIB mstr_standard
J 0
(-6350 4000);
PAINT MONO (-6350 4000);
DISPLAY INVISIBLE (-6350 4000);
FORCEPROP 1 LAST OFFPAGE TRUE
J 0
(-6025 3875);
DISPLAY 1.170213 (-6025 3875);
PAINT GREEN (-6025 3875);
DISPLAY INVISIBLE (-6025 3875);
FORCEPROP 1 LAST COMMENT_BODY TRUE
J 0
(-6225 3900);
DISPLAY 1.170213 (-6225 3900);
PAINT PEACH (-6225 3900);
DISPLAY INVISIBLE (-6225 3900);
FORCEADD OFFPAGE..3
(-2125 2750);
FORCEPROP 2 LAST $XR1 157 
J 0
(-1821 2750);
DISPLAY 0.638298 (-1821 2750);
PAINT MONO (-1821 2750);
FORCEPROP 2 LAST $XR0 97 
J 0
(-1911 2750);
DISPLAY 0.638298 (-1911 2750);
PAINT MONO (-1911 2750);
FORCEPROP 2 LAST PATH I80
J 0
(-1950 2825);
DISPLAY 1.361702 (-1950 2825);
PAINT ORANGE (-1950 2825);
DISPLAY INVISIBLE (-1950 2825);
FORCEPROP 2 LAST CDS_LIB mstr_standard
J 0
(-2125 2750);
PAINT MONO (-2125 2750);
DISPLAY INVISIBLE (-2125 2750);
FORCEPROP 1 LAST OFFPAGE TRUE
J 0
(-1800 2625);
DISPLAY 1.170213 (-1800 2625);
PAINT GREEN (-1800 2625);
DISPLAY INVISIBLE (-1800 2625);
FORCEPROP 1 LAST COMMENT_BODY TRUE
J 0
(-2175 2650);
DISPLAY 1.170213 (-2175 2650);
PAINT PEACH (-2175 2650);
DISPLAY INVISIBLE (-2175 2650);
FORCEADD OFFPAGE..5
(-6350 3900);
FORCEPROP 2 LAST $XR5 48 
J 0
(-7024 3900);
DISPLAY 0.638298 (-7024 3900);
PAINT MONO (-7024 3900);
FORCEPROP 2 LAST $XR4 47 
J 0
(-6934 3900);
DISPLAY 0.638298 (-6934 3900);
PAINT MONO (-6934 3900);
FORCEPROP 2 LAST $XR3 46 
J 0
(-6844 3900);
DISPLAY 0.638298 (-6844 3900);
PAINT MONO (-6844 3900);
FORCEPROP 2 LAST $XR2 45 
J 0
(-6754 3900);
DISPLAY 0.638298 (-6754 3900);
PAINT MONO (-6754 3900);
FORCEPROP 2 LAST $XR1 44 
J 0
(-6664 3900);
DISPLAY 0.638298 (-6664 3900);
PAINT MONO (-6664 3900);
FORCEPROP 2 LAST $XR0 43 
J 0
(-6574 3900);
DISPLAY 0.638298 (-6574 3900);
PAINT MONO (-6574 3900);
FORCEPROP 2 LAST PATH I9
J 0
(-6300 3975);
DISPLAY 1.361702 (-6300 3975);
PAINT ORANGE (-6300 3975);
DISPLAY INVISIBLE (-6300 3975);
FORCEPROP 2 LAST CDS_LIB mstr_standard
J 0
(-6350 3900);
PAINT MONO (-6350 3900);
DISPLAY INVISIBLE (-6350 3900);
FORCEPROP 1 LAST OFFPAGE TRUE
J 0
(-6025 3775);
DISPLAY 1.170213 (-6025 3775);
PAINT GREEN (-6025 3775);
DISPLAY INVISIBLE (-6025 3775);
FORCEPROP 1 LAST COMMENT_BODY TRUE
J 0
(-6250 3825);
DISPLAY 1.170213 (-6250 3825);
PAINT PEACH (-6250 3825);
DISPLAY INVISIBLE (-6250 3825);
FORCEADD PRELIM..10
(-4065 2840);
PAINT GRAY (-4065 2840);
FORCEPROP 2 LAST CDS_LIB mstr_misc
J 0
(-4065 2840);
PAINT ORANGE (-4065 2840);
DISPLAY INVISIBLE (-4065 2840);
FORCEPROP 1 LAST COMMENT_BODY TRUE
J 0
(-4065 2840);
PAINT PEACH (-4065 2840);
DISPLAY INVISIBLE (-4065 2840);
FORCEADD DESIGN_NOTE..1
(-4675 850);
FORCEPROP 0 LAST L1 CPU SYMBOLS 1-30 ARE PRELIMINARY AND SUBJECT TO CHANGE
J 0
(-4875 725);
DISPLAY 1.021277 (-4875 725);
PAINT ORANGE (-4875 725);
FORCEPROP 2 LAST CDS_LIB mstr_symbols
J 0
(-4675 850);
PAINT ORANGE (-4675 850);
DISPLAY INVISIBLE (-4675 850);
FORCEPROP 1 LAST COMMENT_BODY TRUE
J 0
(-4650 950);
DISPLAY 0.978723 (-4650 950);
PAINT ORANGE (-4650 950);
DISPLAY INVISIBLE (-4650 950);
FORCEADD CAD_NOTE..1
(-7600 2625);
FORCEPROP 0 LAST LINE2 WITHIN 1 IN OF CPU PINS
J 0
(-7750 2425);
PAINT WHITE (-7750 2425);
FORCEPROP 0 LAST LINE PLACE RCOMP RESISTORS
J 0
(-7750 2500);
PAINT WHITE (-7750 2500);
FORCEPROP 2 LAST CDS_LIB mstr_symbols
J 0
(-7600 2625);
PAINT ORANGE (-7600 2625);
DISPLAY INVISIBLE (-7600 2625);
FORCEPROP 1 LAST COMMENT_BODY TRUE
J 0
(-7575 2725);
DISPLAY 1.340426 (-7575 2725);
PAINT GREEN (-7575 2725);
DISPLAY INVISIBLE (-7575 2725);
FORCEADD DESIGN_NOTE..1
(-1075 2050);
FORCEPROP 0 LAST L1 CPU0 PIROM ADDRESS: 0XA0
J 0
(-1275 1925);
DISPLAY 0.808511 (-1275 1925);
PAINT ORANGE (-1275 1925);
FORCEPROP 2 LAST CDS_LIB mstr_symbols
J 0
(-1075 2050);
PAINT ORANGE (-1075 2050);
DISPLAY INVISIBLE (-1075 2050);
FORCEPROP 1 LAST COMMENT_BODY TRUE
J 0
(-1050 2150);
DISPLAY 0.978723 (-1050 2150);
PAINT ORANGE (-1050 2150);
DISPLAY INVISIBLE (-1050 2150);
FORCEADD CAD_NOTE..1
(-7725 1625);
FORCEPROP 0 LAST LINE PLACE RBIAS RESISTORS
J 0
(-7875 1500);
PAINT WHITE (-7875 1500);
FORCEPROP 0 LAST LINE2 WITHIN 1.1 IN OF CPU PINS
J 0
(-7875 1425);
PAINT WHITE (-7875 1425);
FORCEPROP 2 LAST CDS_LIB mstr_symbols
J 0
(-7725 1625);
PAINT ORANGE (-7725 1625);
DISPLAY INVISIBLE (-7725 1625);
FORCEPROP 1 LAST COMMENT_BODY TRUE
J 0
(-7700 1725);
DISPLAY 1.340426 (-7700 1725);
PAINT GREEN (-7700 1725);
DISPLAY INVISIBLE (-7700 1725);
FORCEADD INTEL_CORP_BPAGE..1
(-50 0);
FORCEPROP 1 LAST CDS_CON_LAST_MODIFIED Fri Jun 16 17:48:06 2017
J 0
(-1475 325);
DISPLAY 1.340426 (-1475 325);
PAINT GREEN (-1475 325);
DISPLAY INVISIBLE (-1475 325);
FORCEPROP 1 LAST CUSTOM_TXT_CDS <CURRENT_DESIGN_SHEET> OF <TOTAL_DESIGN_SHEETS>
J 0
(-550 25);
PAINT ORANGE (-550 25);
FORCEPROP 1 LAST CUSTOM_TXT_CDS <CON_LAST_MODIFIED>
J 0
(-4050 100);
PAINT ORANGE (-4050 100);
FORCEPROP 2 LAST CUSTOM_TXT_CDS <XR_PAGE_TITLE>
J 0
(-7940 5250);
DISPLAY 0.638298 (-7940 5250);
PAINT PINK (-7940 5250);
DISPLAY INVISIBLE (-7940 5250);
FORCEPROP 1 LAST SCH_TITLE SKYLAKE - SKT0 - 1 OF 21
J 0
(-8000 50);
DISPLAY 1.212766 (-8000 50);
PAINT YELLOW (-8000 50);
FORCEPROP 2 LAST PAGE_BORDER TRUE
J 0
(-7940 5250);
DISPLAY 0.851064 (-7940 5250);
PAINT PINK (-7940 5250);
DISPLAY INVISIBLE (-7940 5250);
FORCEPROP 2 LAST CDS_LIB mstr_symbols
J 0
(-50 0);
PAINT ORANGE (-50 0);
DISPLAY INVISIBLE (-50 0);
FORCEPROP 1 LAST COMMENT_BODY TRUE
J 0
(-38 12);
DISPLAY 0.638298 (-38 12);
PAINT PEACH (-38 12);
DISPLAY INVISIBLE (-38 12);
FORCEPROP 2 LAST CDS_XR_PAGE_TITLE CR-21 : @BASEBOARD_FAB2_LIB.BASEBOARD_FAB2(SCH_1):PAGE21
J 0
(-7940 5250);
DISPLAY 0.638298 (-7940 5250);
PAINT PINK (-7940 5250);
DISPLAY INVISIBLE (-7940 5250);
FORCEADD BOM_NOTE..1
(-7725 4850);
FORCEPROP 0 LAST L1 ASSEMBLY IPN PRIMARY :H63715-002,
J 0
(-7875 4725);
DISPLAY 0.851064 (-7875 4725);
PAINT WHITE (-7875 4725);
FORCEPROP 2 LAST BOM_COST SB
J 0
(-7875 4825);
DISPLAY 1.361702 (-7875 4825);
PAINT ORANGE (-7875 4825);
DISPLAY INVISIBLE (-7875 4825);
FORCEPROP 2 LAST ROOM SB_HEADERS
J 0
(-7875 4825);
DISPLAY 1.361702 (-7875 4825);
PAINT ORANGE (-7875 4825);
DISPLAY INVISIBLE (-7875 4825);
FORCEPROP 2 LAST CDS_LIB mstr_symbols
J 0
(-7725 4850);
PAINT ORANGE (-7725 4850);
DISPLAY INVISIBLE (-7725 4850);
FORCEPROP 1 LAST COMMENT_BODY TRUE
J 0
(-7700 4950);
DISPLAY 1.319149 (-7700 4950);
PAINT ORANGE (-7700 4950);
DISPLAY INVISIBLE (-7700 4950);
WIRE 16 -1 (-900 4550)(-900 4600);
WIRE 16 -1 (-750 4550)(-900 4550);
WIRE 16 -1 (-900 4550)(-1000 4550);
WIRE 16 -1 (-1000 4400)(-1000 4550);
WIRE 16 -1 (-750 4400)(-750 4550);
WIRE 16 -1 (-7800 2700)(-7800 2650);
WIRE 16 -1 (-7800 2700)(-7575 2700);
WIRE 16 -1 (-7800 2900)(-7800 2700);
WIRE 16 -1 (-7575 2700)(-7350 2700);
WIRE 16 -1 (-7575 2900)(-7575 2700);
WIRE 16 -1 (-7350 2700)(-7125 2700);
WIRE 16 -1 (-7350 2825)(-7350 2700);
WIRE 16 -1 (-7125 2700)(-6875 2700);
WIRE 16 -1 (-7125 2825)(-7125 2700);
WIRE 16 -1 (-6625 2700)(-6875 2700);
WIRE 16 -1 (-6875 2825)(-6875 2700);
WIRE 16 -1 (-6625 2700)(-6625 2775);
WIRE 16 -1 (-7800 1775)(-7800 1800);
WIRE 16 -1 (-7800 1800)(-7575 1800);
WIRE 16 -1 (-7800 2100)(-7800 1800);
WIRE 16 -1 (-7575 1800)(-7350 1800);
WIRE 16 -1 (-7575 2000)(-7575 1800);
WIRE 16 -1 (-7350 1800)(-7125 1800);
WIRE 16 -1 (-7350 1900)(-7350 1800);
WIRE 16 -1 (-6900 1800)(-7125 1800);
WIRE 16 -1 (-7125 1900)(-7125 1800);
WIRE 16 -1 (-6900 1900)(-6900 1800);
WIRE 16 -1 (-700 2950)(-700 2900);
WIRE 16 -1 (-700 2900)(-950 2900);
WIRE 16 -1 (-700 2800)(-700 2900);
WIRE 16 -1 (-950 2900)(-1200 2900);
WIRE 16 -1 (-950 2900)(-950 2800);
WIRE 16 -1 (-1200 2900)(-1450 2900);
WIRE 16 -1 (-1200 2800)(-1200 2900);
WIRE 16 -1 (-1700 2900)(-1450 2900);
WIRE 16 -1 (-1450 2800)(-1450 2900);
WIRE 16 -1 (-1700 2800)(-1700 2900);
WIRE 16 -1 (-1075 1550)(-1075 1675);
WIRE 16 -1 (-375 3350)(-375 3200);
WIRE 16 -1 (-375 3200)(-750 3200);
WIRE 16 -1 (-1000 3200)(-750 3200);
WIRE 16 -1 (-750 3400)(-750 3200);
WIRE 16 -1 (-1000 3400)(-1000 3200);
WIRE 16 -1 (-5025 3500)(-6300 3500);
FORCEPROP 2 LAST SIG_NAME M_D_CPU_VREF
J 0
(-6275 3510);
DISPLAY 0.617021 (-6275 3510);
PAINT ORANGE (-6275 3510);
WIRE 16 -1 (-2725 550)(-475 550);
WIRE 16 -1 (-475 550)(-475 1025);
WIRE 16 -1 (-2725 1025)(-2725 550);
WIRE 16 -1 (-2725 1025)(-475 1025);
WIRE 16 -1 (-3125 3350)(-1875 3350);
FORCEPROP 2 LAST SIG_NAME H_CPU0_MSMI_G_N
J 0
(-2950 3360);
DISPLAY 0.617021 (-2950 3360);
PAINT ORANGE (-2950 3360);
WIRE 16 -1 (-5025 3550)(-6300 3550);
FORCEPROP 2 LAST SIG_NAME M_E_CPU_VREF
J 0
(-6275 3560);
DISPLAY 0.617021 (-6275 3560);
PAINT ORANGE (-6275 3560);
WIRE 16 -1 (-5025 4050)(-6300 4050);
FORCEPROP 2 LAST SIG_NAME PWRGD_CPU0_DRAMPWROK_ABC_G
J 0
(-6275 4060);
DISPLAY 0.617021 (-6275 4060);
PAINT ORANGE (-6275 4060);
WIRE 16 -1 (-1450 4500)(-3125 4500);
FORCEPROP 2 LAST SIG_NAME PWRGD_CPU0_G
J 0
(-2950 4510);
DISPLAY 0.617021 (-2950 4510);
PAINT ORANGE (-2950 4510);
WIRE 16 -1 (-5025 4150)(-6300 4150);
FORCEPROP 2 LAST SIG_NAME CLK_100M_CPU0_BCLK2_DN
J 0
(-6275 4160);
DISPLAY 0.617021 (-6275 4160);
PAINT ORANGE (-6275 4160);
WIRE 16 -1 (-7800 3100)(-7800 3250);
WIRE 16 -1 (-5025 3250)(-7800 3250);
FORCEPROP 2 LAST SIG_NAME A_CPU0_ABC_RCOMP2
J 0
(-6250 3260);
DISPLAY 0.617021 (-6250 3260);
PAINT ORANGE (-6250 3260);
FORCEPROP 2 LASTPROP $XRERR UNIQUE?
J 0
(-6490 3260);
DISPLAY 0.638298 (-6490 3260);
PAINT MONO (-6490 3260);
DISPLAY INVISIBLE (-6490 3260);
WIRE 16 -1 (-2100 4000)(-3125 4000);
FORCEPROP 2 LAST SIG_NAME SVID_DIO1_CPU0
J 0
(-2950 4010);
DISPLAY 0.617021 (-2950 4010);
PAINT ORANGE (-2950 4010);
FORCEPROP 2 LASTPROP $XRERR UNIQUE?
J 0
(-3190 4010);
DISPLAY 0.638298 (-3190 4010);
PAINT MONO (-3190 4010);
DISPLAY INVISIBLE (-3190 4010);
WIRE 16 -1 (-3125 2300)(-1200 2300);
FORCEPROP 2 LAST SIG_NAME FM_CPU0_PKGID2
J 0
(-2950 2310);
DISPLAY 0.617021 (-2950 2310);
PAINT ORANGE (-2950 2310);
WIRE 16 -1 (-600 2300)(-1200 2300);
WIRE 16 -1 (-1200 2600)(-1200 2300);
WIRE 16 -1 (-750 3600)(-750 3750);
WIRE 16 -1 (-675 3750)(-750 3750);
WIRE 16 -1 (-1900 3750)(-750 3750);
FORCEPROP 2 LAST SIG_NAME SVID_ALERT0_CPU0_R_N
J 0
(-1475 3760);
DISPLAY 0.617021 (-1475 3760);
PAINT ORANGE (-1475 3760);
WIRE 16 -1 (-1900 3850)(-1000 3850);
FORCEPROP 2 LAST SIG_NAME SVID_DIO0_CPU0_R
J 0
(-1475 3860);
DISPLAY 0.617021 (-1475 3860);
PAINT ORANGE (-1475 3860);
WIRE 16 -1 (-700 3850)(-1000 3850);
WIRE 16 -1 (-1000 3600)(-1000 3850);
WIRE 16 -1 (-1900 3800)(-675 3800);
FORCEPROP 2 LAST SIG_NAME SVID_CLK0_CPU0_R
J 0
(-1475 3810);
DISPLAY 0.617021 (-1475 3810);
PAINT ORANGE (-1475 3810);
WIRE 16 -1 (-1900 3950)(-675 3950);
FORCEPROP 2 LAST SIG_NAME SVID_CLK1_CPU0_R
J 0
(-1475 3960);
DISPLAY 0.617021 (-1475 3960);
PAINT ORANGE (-1475 3960);
WIRE 16 -1 (-700 4000)(-1000 4000);
WIRE 16 -1 (-1000 4200)(-1000 4000);
WIRE 16 -1 (-1900 4000)(-1000 4000);
FORCEPROP 2 LAST SIG_NAME SVID_DIO1_CPU0_R
J 0
(-1475 4010);
DISPLAY 0.617021 (-1475 4010);
PAINT ORANGE (-1475 4010);
WIRE 16 -1 (-600 2200)(-700 2200);
WIRE 16 -1 (-700 2600)(-700 2200);
WIRE 16 -1 (-3125 2200)(-700 2200);
FORCEPROP 2 LAST SIG_NAME FM_CPU0_PKGID0
J 0
(-2950 2210);
DISPLAY 0.617021 (-2950 2210);
PAINT ORANGE (-2950 2210);
WIRE 16 -1 (-2125 2650)(-3125 2650);
FORCEPROP 2 LAST SIG_NAME PU_CPU0_SOCKET_ID_1
J 0
(-2950 2660);
DISPLAY 0.617021 (-2950 2660);
PAINT ORANGE (-2950 2660);
WIRE 16 -1 (-2125 2600)(-3125 2600);
FORCEPROP 2 LAST SIG_NAME PU_CPU0_SOCKET_ID_0
J 0
(-2950 2610);
DISPLAY 0.617021 (-2950 2610);
PAINT ORANGE (-2950 2610);
WIRE 16 -1 (-1450 2400)(-3125 2400);
FORCEPROP 2 LAST SIG_NAME FM_CPU0_PROC_ID0
J 0
(-2950 2410);
DISPLAY 0.617021 (-2950 2410);
PAINT ORANGE (-2950 2410);
WIRE 16 -1 (-1450 2600)(-1450 2400);
WIRE 16 -1 (-600 2400)(-1450 2400);
WIRE 16 -1 (-1850 2100)(-3125 2100);
FORCEPROP 2 LAST SIG_NAME PU_CPU0_TSC_SYNC
J 0
(-2948 2115);
DISPLAY 0.617021 (-2948 2115);
PAINT ORANGE (-2948 2115);
WIRE 16 -1 (-1850 2050)(-3125 2050);
FORCEPROP 2 LAST SIG_NAME FM_CPU0_SM_WP
J 0
(-2950 2060);
DISPLAY 0.617021 (-2950 2060);
PAINT ORANGE (-2950 2060);
WIRE 16 -1 (-1850 1950)(-3125 1950);
FORCEPROP 2 LAST SIG_NAME TP_NMI_CPU0
J 0
(-2950 1960);
DISPLAY 0.617021 (-2950 1960);
PAINT ORANGE (-2950 1960);
FORCEPROP 2 LASTPROP $XRERR UNIQUE?
J 0
(-1820 1950);
DISPLAY 0.638298 (-1820 1950);
PAINT MONO (-1820 1950);
DISPLAY INVISIBLE (-1820 1950);
WIRE 16 -1 (-6300 3400)(-5025 3400);
FORCEPROP 2 LAST SIG_NAME M_B_CPU_VREF
J 0
(-6275 3410);
DISPLAY 0.617021 (-6275 3410);
PAINT ORANGE (-6275 3410);
WIRE 16 -1 (-2675 900)(-525 900);
WIRE 16 -1 (-5025 2500)(-6275 2500);
FORCEPROP 2 LAST SIG_NAME SMB_PIROM_CPU0_SCL
J 0
(-6250 2510);
DISPLAY 0.617021 (-6250 2510);
PAINT ORANGE (-6250 2510);
WIRE 16 -1 (-5025 2450)(-6275 2450);
FORCEPROP 2 LAST SIG_NAME SMB_PIROM_CPU0_SDA
J 0
(-6250 2460);
DISPLAY 0.617021 (-6250 2460);
PAINT ORANGE (-6250 2460);
WIRE 16 -1 (-5025 2650)(-6300 2650);
FORCEPROP 2 LAST SIG_NAME SMB_CPU0_PE_HP_GTL_SCL
J 0
(-6250 2660);
DISPLAY 0.617021 (-6250 2660);
PAINT ORANGE (-6250 2660);
WIRE 16 -1 (-5025 2600)(-6275 2600);
FORCEPROP 2 LAST SIG_NAME SMB_CPU0_PE_HP_GTL_SDA
J 0
(-6250 2610);
DISPLAY 0.617021 (-6250 2610);
PAINT ORANGE (-6250 2610);
WIRE 16 -1 (-6325 1800)(-5025 1800);
FORCEPROP 2 LAST SIG_NAME XDP_CPU_OBSFN_B1_MBP7_N
J 0
(-6300 1810);
DISPLAY 0.617021 (-6300 1810);
PAINT ORANGE (-6300 1810);
WIRE 16 -1 (-6325 1700)(-5025 1700);
FORCEPROP 2 LAST SIG_NAME TP_XDP_CPU0_OBSDATA_A3_MBP5_N
J 0
(-6300 1710);
DISPLAY 0.617021 (-6300 1710);
PAINT ORANGE (-6300 1710);
FORCEPROP 2 LASTPROP $XRERR UNIQUE?
J 0
(-6565 1700);
DISPLAY 0.638298 (-6565 1700);
PAINT MONO (-6565 1700);
DISPLAY INVISIBLE (-6565 1700);
WIRE 16 -1 (-6325 1650)(-5025 1650);
FORCEPROP 2 LAST SIG_NAME TP_XDP_CPU0_OBSDATA_A2_MBP4_N
J 0
(-6300 1660);
DISPLAY 0.617021 (-6300 1660);
PAINT ORANGE (-6300 1660);
FORCEPROP 2 LASTPROP $XRERR UNIQUE?
J 0
(-6565 1650);
DISPLAY 0.638298 (-6565 1650);
PAINT MONO (-6565 1650);
DISPLAY INVISIBLE (-6565 1650);
WIRE 16 -1 (-5025 3700)(-6275 3700);
FORCEPROP 2 LAST SIG_NAME H_CPU0_MEMDEF_MEMHOT_G_N
J 0
(-6250 3710);
DISPLAY 0.617021 (-6250 3710);
PAINT ORANGE (-6250 3710);
WIRE 16 -1 (-6300 3600)(-5025 3600);
FORCEPROP 2 LAST SIG_NAME M_F_CPU_VREF
J 0
(-6275 3610);
DISPLAY 0.617021 (-6275 3610);
PAINT ORANGE (-6275 3610);
WIRE 16 -1 (-5025 3750)(-6275 3750);
FORCEPROP 2 LAST SIG_NAME H_CPU0_MEMABC_MEMHOT_G_N
J 0
(-6250 3760);
DISPLAY 0.617021 (-6250 3760);
PAINT ORANGE (-6250 3760);
WIRE 16 -1 (-5025 3850)(-6300 3850);
FORCEPROP 2 LAST SIG_NAME M_DEF_RST_N
J 0
(-6275 3860);
DISPLAY 0.617021 (-6275 3860);
PAINT ORANGE (-6275 3860);
WIRE 16 -1 (-5025 4000)(-6300 4000);
FORCEPROP 2 LAST SIG_NAME PWRGD_CPU0_DRAMPWROK_DEF_G
J 0
(-6275 4010);
DISPLAY 0.617021 (-6275 4010);
PAINT ORANGE (-6275 4010);
WIRE 16 -1 (-5025 1200)(-6325 1200);
FORCEPROP 2 LAST SIG_NAME XDP_CPU_TRST_N
J 0
(-6300 1210);
DISPLAY 0.617021 (-6300 1210);
PAINT ORANGE (-6300 1210);
WIRE 16 -1 (-6325 1300)(-5025 1300);
FORCEPROP 2 LAST SIG_NAME XDP_CPU_TCK0
J 0
(-6300 1310);
DISPLAY 0.617021 (-6300 1310);
PAINT ORANGE (-6300 1310);
WIRE 16 -1 (-6325 1450)(-5025 1450);
FORCEPROP 2 LAST SIG_NAME XDP_CPU_MBP0_N
J 0
(-6300 1460);
DISPLAY 0.617021 (-6300 1460);
PAINT ORANGE (-6300 1460);
WIRE 16 -1 (-6325 1550)(-5025 1550);
FORCEPROP 2 LAST SIG_NAME TP_XDP_CPU0_OBSDATA_A0_MBP2_N
J 0
(-6300 1560);
DISPLAY 0.617021 (-6300 1560);
PAINT ORANGE (-6300 1560);
FORCEPROP 2 LASTPROP $XRERR UNIQUE?
J 0
(-6565 1550);
DISPLAY 0.638298 (-6565 1550);
PAINT MONO (-6565 1550);
DISPLAY INVISIBLE (-6565 1550);
WIRE 16 -1 (-6325 1600)(-5025 1600);
FORCEPROP 2 LAST SIG_NAME TP_XDP_CPU0_OBSDATA_A1_MBP3_N
J 0
(-6300 1610);
DISPLAY 0.617021 (-6300 1610);
PAINT ORANGE (-6300 1610);
FORCEPROP 2 LASTPROP $XRERR UNIQUE?
J 0
(-6565 1600);
DISPLAY 0.638298 (-6565 1600);
PAINT MONO (-6565 1600);
DISPLAY INVISIBLE (-6565 1600);
WIRE 16 -1 (-5575 1900)(-5025 1900);
WIRE 16 -1 (-5575 1950)(-5575 1900);
WIRE 16 -1 (-5025 1950)(-5575 1950);
WIRE 16 -1 (-5575 1950)(-5575 2150);
WIRE 16 -1 (-6900 2150)(-5575 2150);
FORCEPROP 2 LAST SIG_NAME A_CPU0_MCP01_RBIAS
J 0
(-6500 2160);
DISPLAY 0.617021 (-6500 2160);
PAINT ORANGE (-6500 2160);
FORCEPROP 2 LASTPROP $XRERR UNIQUE?
J 0
(-6740 2160);
DISPLAY 0.638298 (-6740 2160);
PAINT MONO (-6740 2160);
DISPLAY INVISIBLE (-6740 2160);
WIRE 16 -1 (-6900 2100)(-6900 2150);
WIRE 16 -1 (-5025 2850)(-5975 2850);
FORCEPROP 2 LAST SIG_NAME SMB_DDR_ABC_SDA_G_R
J 0
(-5950 2860);
DISPLAY 0.617021 (-5950 2860);
PAINT ORANGE (-5950 2860);
WIRE 16 -1 (-5025 2900)(-5975 2900);
FORCEPROP 2 LAST SIG_NAME SMB_DDR_DEF_SDA_G_R
J 0
(-5950 2910);
DISPLAY 0.617021 (-5950 2910);
PAINT ORANGE (-5950 2910);
WIRE 16 -1 (-5975 2750)(-5025 2750);
FORCEPROP 2 LAST SIG_NAME SMB_DDR_ABC_SCL_G_R
J 0
(-5950 2760);
DISPLAY 0.617021 (-5950 2760);
PAINT ORANGE (-5950 2760);
WIRE 16 -1 (-5025 2800)(-5975 2800);
FORCEPROP 2 LAST SIG_NAME SMB_DDR_DEF_SCL_G_R
J 0
(-5950 2810);
DISPLAY 0.617021 (-5950 2810);
PAINT ORANGE (-5950 2810);
WIRE 16 -1 (-5025 4200)(-6300 4200);
FORCEPROP 2 LAST SIG_NAME CLK_100M_CPU0_BCLK2_DP
J 0
(-6275 4210);
DISPLAY 0.617021 (-6275 4210);
PAINT ORANGE (-6275 4210);
WIRE 16 -1 (-5025 4350)(-6300 4350);
FORCEPROP 2 LAST SIG_NAME CLK_100M_CPU0_BCLK1_DP
J 0
(-6275 4360);
DISPLAY 0.617021 (-6275 4360);
PAINT ORANGE (-6275 4360);
WIRE 16 -1 (-5025 4450)(-6300 4450);
FORCEPROP 2 LAST SIG_NAME CLK_100M_CPU0_BCLK0_DN
J 0
(-6275 4460);
DISPLAY 0.617021 (-6275 4460);
PAINT ORANGE (-6275 4460);
WIRE 16 -1 (-5025 4500)(-6300 4500);
FORCEPROP 2 LAST SIG_NAME CLK_100M_CPU0_BCLK0_DP
J 0
(-6275 4510);
DISPLAY 0.617021 (-6275 4510);
PAINT ORANGE (-6275 4510);
WIRE 16 -1 (-5025 4300)(-6300 4300);
FORCEPROP 2 LAST SIG_NAME CLK_100M_CPU0_BCLK1_DN
J 0
(-6275 4310);
DISPLAY 0.617021 (-6275 4310);
PAINT ORANGE (-6275 4310);
WIRE 16 -1 (-2275 1000)(-2275 575);
WIRE 16 -1 (-3125 3050)(-2150 3050);
FORCEPROP 2 LAST SIG_NAME PU_CPU0_SAFE_MODE_BOOT
J 0
(-2950 3060);
DISPLAY 0.617021 (-2950 3060);
PAINT ORANGE (-2950 3060);
WIRE 16 -1 (-3125 1650)(-1850 1650);
FORCEPROP 2 LAST SIG_NAME PD_CPU0_KSFC_DIS
J 0
(-2940 1652);
DISPLAY 0.617021 (-2940 1652);
PAINT ORANGE (-2940 1652);
WIRE 16 -1 (-1850 1700)(-3125 1700);
FORCEPROP 2 LAST SIG_NAME PD_PIROM_CPU0_ADDR0
J 0
(-2950 1710);
DISPLAY 0.617021 (-2950 1710);
PAINT ORANGE (-2950 1710);
WIRE 16 -1 (-1850 1900)(-3125 1900);
FORCEPROP 2 LAST SIG_NAME PU_CPU0_LEGACY_SKT
J 0
(-2950 1910);
DISPLAY 0.617021 (-2950 1910);
PAINT ORANGE (-2950 1910);
WIRE 16 -1 (-1850 1350)(-3125 1350);
FORCEPROP 2 LAST SIG_NAME XDP_CPU_PRDY_N
J 0
(-2950 1360);
DISPLAY 0.617021 (-2950 1360);
PAINT ORANGE (-2950 1360);
WIRE 16 -1 (-1850 1550)(-3125 1550);
FORCEPROP 2 LAST SIG_NAME PD_CPU0_TEST13
J 0
(-2950 1560);
DISPLAY 0.617021 (-2950 1560);
PAINT ORANGE (-2950 1560);
WIRE 16 -1 (-1850 1500)(-3125 1500);
FORCEPROP 2 LAST SIG_NAME PD_CPU0_TEST12
J 0
(-2950 1510);
DISPLAY 0.617021 (-2950 1510);
PAINT ORANGE (-2950 1510);
WIRE 16 -1 (-3125 1600)(-1850 1600);
FORCEPROP 2 LAST SIG_NAME PD_CPU0_TEST14
J 0
(-2950 1610);
DISPLAY 0.617021 (-2950 1610);
PAINT ORANGE (-2950 1610);
WIRE 16 -1 (-1850 1400)(-3125 1400);
FORCEPROP 2 LAST SIG_NAME XDP_CPU_PREQ_N
J 0
(-2950 1410);
DISPLAY 0.617021 (-2950 1410);
PAINT ORANGE (-2950 1410);
WIRE 16 -1 (-1850 1800)(-3125 1800);
FORCEPROP 2 LAST SIG_NAME PD_PIROM_CPU0_ADDR2
J 0
(-2950 1810);
DISPLAY 0.617021 (-2950 1810);
PAINT ORANGE (-2950 1810);
WIRE 16 -1 (-1850 1750)(-3125 1750);
FORCEPROP 2 LAST SIG_NAME PD_PIROM_CPU0_ADDR1
J 0
(-2950 1760);
DISPLAY 0.617021 (-2950 1760);
PAINT ORANGE (-2950 1760);
WIRE 16 -1 (-1850 3500)(-3125 3500);
FORCEPROP 2 LAST SIG_NAME H_CPU0_ERR1_G_N
J 0
(-2950 3510);
DISPLAY 0.617021 (-2950 3510);
PAINT ORANGE (-2950 3510);
WIRE 16 -1 (-1050 1000)(-1050 575);
WIRE 16 -1 (-3125 2450)(-1700 2450);
FORCEPROP 2 LAST SIG_NAME FM_CPU0_PROC_ID1
J 0
(-2950 2460);
DISPLAY 0.617021 (-2950 2460);
PAINT ORANGE (-2950 2460);
WIRE 16 -1 (-600 2450)(-1700 2450);
WIRE 16 -1 (-1700 2600)(-1700 2450);
WIRE 16 -1 (-950 2250)(-3125 2250);
FORCEPROP 2 LAST SIG_NAME FM_CPU0_PKGID1
J 0
(-2950 2260);
DISPLAY 0.617021 (-2950 2260);
PAINT ORANGE (-2950 2260);
WIRE 16 -1 (-600 2250)(-950 2250);
WIRE 16 -1 (-950 2600)(-950 2250);
WIRE 16 -1 (-3125 4250)(-2175 4250);
FORCEPROP 2 LAST SIG_NAME H_PM_SYNC_GTL_R1
J 0
(-2950 4260);
DISPLAY 0.617021 (-2950 4260);
PAINT ORANGE (-2950 4260);
FORCEPROP 2 LASTPROP $XRERR UNIQUE?
J 0
(-3190 4260);
DISPLAY 0.638298 (-3190 4260);
PAINT MONO (-3190 4260);
DISPLAY INVISIBLE (-3190 4260);
WIRE 16 -1 (-2175 4200)(-3125 4200);
FORCEPROP 2 LAST SIG_NAME H_PMSYNC_CLK_24M_CPU0
J 0
(-2950 4210);
DISPLAY 0.617021 (-2950 4210);
PAINT ORANGE (-2950 4210);
FORCEPROP 2 LASTPROP $XRERR UNIQUE?
J 0
(-3190 4210);
DISPLAY 0.638298 (-3190 4210);
PAINT MONO (-3190 4210);
DISPLAY INVISIBLE (-3190 4210);
WIRE 16 -1 (-1850 3450)(-3125 3450);
FORCEPROP 2 LAST SIG_NAME H_CPU0_ERR0_G_N
J 0
(-2950 3460);
DISPLAY 0.617021 (-2950 3460);
PAINT ORANGE (-2950 3460);
WIRE 16 -1 (-1450 4250)(-1975 4250);
FORCEPROP 2 LAST SIG_NAME H_PM_SYNC_GTL
J 0
(-1910 4260);
DISPLAY 0.617021 (-1910 4260);
PAINT ORANGE (-1910 4260);
WIRE 16 -1 (-1450 4350)(-3125 4350);
FORCEPROP 2 LAST SIG_NAME PD_CPU0_EAR_N
J 0
(-2950 4360);
DISPLAY 0.617021 (-2950 4360);
PAINT ORANGE (-2950 4360);
WIRE 16 -1 (-1450 4450)(-3125 4450);
FORCEPROP 2 LAST SIG_NAME RST_CPU0_G_N
J 0
(-2950 4460);
DISPLAY 0.617021 (-2950 4460);
PAINT ORANGE (-2950 4460);
WIRE 16 -1 (-5025 3900)(-6300 3900);
FORCEPROP 2 LAST SIG_NAME M_ABC_RST_N
J 0
(-6275 3910);
DISPLAY 0.617021 (-6275 3910);
PAINT ORANGE (-6275 3910);
WIRE 16 -1 (-1500 1000)(-1500 575);
WIRE 16 -1 (-2675 825)(-525 825);
WIRE 16 -1 (-2675 625)(-525 625);
WIRE 16 -1 (-2675 700)(-550 700);
WIRE 16 -1 (-3125 3250)(-1850 3250);
FORCEPROP 2 LAST SIG_NAME TP_CPU0_PROCDIS_G_N
J 0
(-2950 3260);
DISPLAY 0.617021 (-2950 3260);
PAINT ORANGE (-2950 3260);
FORCEPROP 2 LASTPROP $XRERR UNIQUE?
J 0
(-1820 3250);
DISPLAY 0.638298 (-1820 3250);
PAINT MONO (-1820 3250);
DISPLAY INVISIBLE (-1820 3250);
WIRE 16 -1 (-3125 3200)(-1875 3200);
FORCEPROP 2 LAST SIG_NAME H_CPU0_PROCHOT_G_N
J 0
(-2950 3210);
DISPLAY 0.617021 (-2950 3210);
PAINT ORANGE (-2950 3210);
WIRE 16 -1 (-2150 2900)(-3125 2900);
FORCEPROP 2 LAST SIG_NAME PU_CPU0_TXT_AGENT
J 0
(-2950 2910);
DISPLAY 0.617021 (-2950 2910);
PAINT ORANGE (-2950 2910);
WIRE 16 -1 (-2150 2850)(-3125 2850);
FORCEPROP 2 LAST SIG_NAME PD_CPU0_TXT_PLTEN
J 0
(-2950 2860);
DISPLAY 0.617021 (-2950 2860);
PAINT ORANGE (-2950 2860);
WIRE 16 -1 (-2150 2800)(-3125 2800);
FORCEPROP 2 LAST SIG_NAME PD_CPU0_BIST_ENABLE
J 0
(-2950 2810);
DISPLAY 0.617021 (-2950 2810);
PAINT ORANGE (-2950 2810);
WIRE 16 -1 (-2175 2750)(-3125 2750);
FORCEPROP 2 LAST SIG_NAME H_CPU0_FAST_WAKE_N
J 0
(-2950 2760);
DISPLAY 0.617021 (-2950 2760);
PAINT ORANGE (-2950 2760);
WIRE 16 -1 (-5025 3150)(-7350 3150);
FORCEPROP 2 LAST SIG_NAME A_CPU0_ABC_RCOMP0
J 0
(-6250 3160);
DISPLAY 0.617021 (-6250 3160);
PAINT ORANGE (-6250 3160);
FORCEPROP 2 LASTPROP $XRERR UNIQUE?
J 0
(-6490 3160);
DISPLAY 0.638298 (-6490 3160);
PAINT MONO (-6490 3160);
DISPLAY INVISIBLE (-6490 3160);
WIRE 16 -1 (-7350 3025)(-7350 3150);
WIRE 16 -1 (-6300 3450)(-5025 3450);
FORCEPROP 2 LAST SIG_NAME M_C_CPU_VREF
J 0
(-6275 3460);
DISPLAY 0.617021 (-6275 3460);
PAINT ORANGE (-6275 3460);
WIRE 16 -1 (-6300 3350)(-5025 3350);
FORCEPROP 2 LAST SIG_NAME M_A_CPU_VREF
J 0
(-6275 3360);
DISPLAY 0.617021 (-6275 3360);
PAINT ORANGE (-6275 3360);
WIRE 16 -1 (-5025 3200)(-7575 3200);
FORCEPROP 2 LAST SIG_NAME A_CPU0_ABC_RCOMP1
J 0
(-6250 3210);
DISPLAY 0.617021 (-6250 3210);
PAINT ORANGE (-6250 3210);
FORCEPROP 2 LASTPROP $XRERR UNIQUE?
J 0
(-6490 3210);
DISPLAY 0.638298 (-6490 3210);
PAINT MONO (-6490 3210);
DISPLAY INVISIBLE (-6490 3210);
WIRE 16 -1 (-7575 3100)(-7575 3200);
WIRE 16 -1 (-5025 3100)(-7125 3100);
FORCEPROP 2 LAST SIG_NAME A_CPU0_DEF_RCOMP2
J 0
(-6250 3110);
DISPLAY 0.617021 (-6250 3110);
PAINT ORANGE (-6250 3110);
FORCEPROP 2 LASTPROP $XRERR UNIQUE?
J 0
(-6490 3110);
DISPLAY 0.638298 (-6490 3110);
PAINT MONO (-6490 3110);
DISPLAY INVISIBLE (-6490 3110);
WIRE 16 -1 (-7125 3025)(-7125 3100);
WIRE 16 -1 (-5025 3050)(-6875 3050);
FORCEPROP 2 LAST SIG_NAME A_CPU0_DEF_RCOMP1
J 0
(-6250 3060);
DISPLAY 0.617021 (-6250 3060);
PAINT ORANGE (-6250 3060);
FORCEPROP 2 LASTPROP $XRERR UNIQUE?
J 0
(-6490 3060);
DISPLAY 0.638298 (-6490 3060);
PAINT MONO (-6490 3060);
DISPLAY INVISIBLE (-6490 3060);
WIRE 16 -1 (-6875 3025)(-6875 3050);
WIRE 16 -1 (-5025 3000)(-6625 3000);
FORCEPROP 2 LAST SIG_NAME A_CPU0_DEF_RCOMP0
J 0
(-6250 3010);
DISPLAY 0.617021 (-6250 3010);
PAINT ORANGE (-6250 3010);
FORCEPROP 2 LASTPROP $XRERR UNIQUE?
J 0
(-6490 3010);
DISPLAY 0.638298 (-6490 3010);
PAINT MONO (-6490 3010);
DISPLAY INVISIBLE (-6490 3010);
WIRE 16 -1 (-6625 2975)(-6625 3000);
WIRE 16 -1 (-7800 2350)(-7800 2300);
WIRE 16 -1 (-7800 2350)(-5275 2350);
FORCEPROP 2 LAST SIG_NAME A_CPU0_PE3_RBIAS
J 0
(-6525 2360);
DISPLAY 0.617021 (-6525 2360);
PAINT ORANGE (-6525 2360);
FORCEPROP 2 LASTPROP $XRERR UNIQUE?
J 0
(-6765 2360);
DISPLAY 0.638298 (-6765 2360);
PAINT MONO (-6765 2360);
DISPLAY INVISIBLE (-6765 2360);
WIRE 16 -1 (-5275 2350)(-5025 2350);
WIRE 16 -1 (-5275 2300)(-5275 2350);
WIRE 16 -1 (-5025 2300)(-5275 2300);
WIRE 16 -1 (-5025 2200)(-5350 2200);
WIRE 16 -1 (-5350 2200)(-5350 2250);
WIRE 16 -1 (-5025 2250)(-5350 2250);
WIRE 16 -1 (-5350 2250)(-5350 2300);
WIRE 16 -1 (-5350 2300)(-7575 2300);
FORCEPROP 2 LAST SIG_NAME A_CPU0_PE012_RBIAS
J 0
(-6525 2310);
DISPLAY 0.617021 (-6525 2310);
PAINT ORANGE (-6525 2310);
FORCEPROP 2 LASTPROP $XRERR UNIQUE?
J 0
(-6765 2310);
DISPLAY 0.638298 (-6765 2310);
PAINT MONO (-6765 2310);
DISPLAY INVISIBLE (-6765 2310);
WIRE 16 -1 (-7575 2200)(-7575 2300);
WIRE 16 -1 (-7125 2100)(-7125 2200);
WIRE 16 -1 (-7125 2200)(-5500 2200);
FORCEPROP 2 LAST SIG_NAME A_CPU0_UPI2_RBIAS
J 0
(-6500 2210);
DISPLAY 0.617021 (-6500 2210);
PAINT ORANGE (-6500 2210);
FORCEPROP 2 LASTPROP $XRERR UNIQUE?
J 0
(-6740 2210);
DISPLAY 0.638298 (-6740 2210);
PAINT MONO (-6740 2210);
DISPLAY INVISIBLE (-6740 2210);
WIRE 16 -1 (-5500 2000)(-5025 2000);
WIRE 16 -1 (-5500 2050)(-5500 2000);
WIRE 16 -1 (-5500 2050)(-5500 2200);
WIRE 16 -1 (-5025 2050)(-5500 2050);
WIRE 16 -1 (-7350 2100)(-7350 2250);
WIRE 16 -1 (-7350 2250)(-5425 2250);
FORCEPROP 2 LAST SIG_NAME A_CPU0_UPI01_RBIAS
J 0
(-6500 2260);
DISPLAY 0.617021 (-6500 2260);
PAINT ORANGE (-6500 2260);
FORCEPROP 2 LASTPROP $XRERR UNIQUE?
J 0
(-6740 2260);
DISPLAY 0.638298 (-6740 2260);
PAINT MONO (-6740 2260);
DISPLAY INVISIBLE (-6740 2260);
WIRE 16 -1 (-5425 2150)(-5425 2250);
WIRE 16 -1 (-5025 2150)(-5425 2150);
WIRE 16 -1 (-5425 2150)(-5425 2100);
WIRE 16 -1 (-5425 2100)(-5025 2100);
WIRE 16 -1 (-6325 1750)(-5025 1750);
FORCEPROP 2 LAST SIG_NAME XDP_CPU_OBSFN_B0_MBP6_N
J 0
(-6300 1760);
DISPLAY 0.617021 (-6300 1760);
PAINT ORANGE (-6300 1760);
WIRE 16 -1 (-6325 1500)(-5025 1500);
FORCEPROP 2 LAST SIG_NAME XDP_CPU_MBP1_N
J 0
(-6300 1510);
DISPLAY 0.617021 (-6300 1510);
PAINT ORANGE (-6300 1510);
WIRE 16 -1 (-5025 1350)(-6325 1350);
FORCEPROP 2 LAST SIG_NAME XDP_CPU_TDI
J 0
(-6300 1360);
DISPLAY 0.617021 (-6300 1360);
PAINT ORANGE (-6300 1360);
WIRE 16 -1 (-6325 1250)(-5025 1250);
FORCEPROP 2 LAST SIG_NAME XDP_CPU_TMS
J 0
(-6300 1260);
DISPLAY 0.617021 (-6300 1260);
PAINT ORANGE (-6300 1260);
WIRE 16 -1 (-1850 1150)(-3125 1150);
FORCEPROP 2 LAST SIG_NAME XDP_CPU0_TDO
J 0
(-2950 1160);
DISPLAY 0.617021 (-2950 1160);
PAINT ORANGE (-2950 1160);
WIRE 16 -1 (-1075 1250)(-3125 1250);
FORCEPROP 2 LAST SIG_NAME FM_CPU0_SKTOCC_LVT3_N
J 0
(-2950 1260);
DISPLAY 0.617021 (-2950 1260);
PAINT ORANGE (-2950 1260);
WIRE 16 -1 (-1075 1350)(-1075 1250);
WIRE 16 -1 (-600 1250)(-1075 1250);
WIRE 16 -1 (-1900 4100)(-3125 4100);
FORCEPROP 2 LAST SIG_NAME PECI_CPU_G
J 0
(-2950 4110);
DISPLAY 0.617021 (-2950 4110);
PAINT ORANGE (-2950 4110);
WIRE 16 -1 (-2100 3950)(-3125 3950);
FORCEPROP 2 LAST SIG_NAME SVID_CLK1_CPU0
J 0
(-2950 3960);
DISPLAY 0.617021 (-2950 3960);
PAINT ORANGE (-2950 3960);
FORCEPROP 2 LASTPROP $XRERR UNIQUE?
J 0
(-3190 3960);
DISPLAY 0.638298 (-3190 3960);
PAINT MONO (-3190 3960);
DISPLAY INVISIBLE (-3190 3960);
WIRE 16 -1 (-2100 3900)(-3125 3900);
FORCEPROP 2 LAST SIG_NAME SVID_ALERT1_CPU0_N
J 0
(-2950 3910);
DISPLAY 0.617021 (-2950 3910);
PAINT ORANGE (-2950 3910);
FORCEPROP 2 LASTPROP $XRERR UNIQUE?
J 0
(-3190 3910);
DISPLAY 0.638298 (-3190 3910);
PAINT MONO (-3190 3910);
DISPLAY INVISIBLE (-3190 3910);
WIRE 16 -1 (-2100 3750)(-3125 3750);
FORCEPROP 2 LAST SIG_NAME SVID_ALERT0_CPU0_N
J 0
(-2950 3760);
DISPLAY 0.617021 (-2950 3760);
PAINT ORANGE (-2950 3760);
FORCEPROP 2 LASTPROP $XRERR UNIQUE?
J 0
(-3190 3760);
DISPLAY 0.638298 (-3190 3760);
PAINT MONO (-3190 3760);
DISPLAY INVISIBLE (-3190 3760);
WIRE 16 -1 (-2100 3800)(-3125 3800);
FORCEPROP 2 LAST SIG_NAME SVID_CLK0_CPU0
J 0
(-2950 3810);
DISPLAY 0.617021 (-2950 3810);
PAINT ORANGE (-2950 3810);
FORCEPROP 2 LASTPROP $XRERR UNIQUE?
J 0
(-3190 3810);
DISPLAY 0.638298 (-3190 3810);
PAINT MONO (-3190 3810);
DISPLAY INVISIBLE (-3190 3810);
WIRE 16 -1 (-1450 4200)(-1975 4200);
FORCEPROP 0 LAST SIG_NAME H_PMSYNC_CLK_24M
J 0
(-1920 4210);
DISPLAY 0.617021 (-1920 4210);
PAINT ORANGE (-1920 4210);
WIRE 16 -1 (-2100 3850)(-3125 3850);
FORCEPROP 2 LAST SIG_NAME SVID_DIO0_CPU0
J 0
(-2950 3860);
DISPLAY 0.617021 (-2950 3860);
PAINT ORANGE (-2950 3860);
FORCEPROP 2 LASTPROP $XRERR UNIQUE?
J 0
(-3190 3860);
DISPLAY 0.638298 (-3190 3860);
PAINT MONO (-3190 3860);
DISPLAY INVISIBLE (-3190 3860);
WIRE 16 -1 (-675 3900)(-750 3900);
WIRE 16 -1 (-750 4200)(-750 3900);
WIRE 16 -1 (-1900 3900)(-750 3900);
FORCEPROP 2 LAST SIG_NAME SVID_ALERT1_CPU0_R_N
J 0
(-1475 3910);
DISPLAY 0.617021 (-1475 3910);
PAINT ORANGE (-1475 3910);
WIRE 16 -1 (-1850 3550)(-3125 3550);
FORCEPROP 2 LAST SIG_NAME H_CPU0_ERR2_G_N
J 0
(-2950 3560);
DISPLAY 0.617021 (-2950 3560);
PAINT ORANGE (-2950 3560);
WIRE 16 -1 (-2200 2550)(-3125 2550);
FORCEPROP 2 LAST SIG_NAME TP_CPU0_SOCKET_ID_2
J 0
(-2950 2560);
DISPLAY 0.617021 (-2950 2560);
PAINT ORANGE (-2950 2560);
FORCEPROP 2 LASTPROP $XRERR UNIQUE?
J 0
(-2170 2550);
DISPLAY 0.638298 (-2170 2550);
PAINT MONO (-2170 2550);
DISPLAY INVISIBLE (-2170 2550);
WIRE 16 -1 (-3125 3650)(-1875 3650);
FORCEPROP 2 LAST SIG_NAME H_CPU0_CATERR_G_N
J 0
(-2950 3660);
DISPLAY 0.617021 (-2950 3660);
PAINT ORANGE (-2950 3660);
WIRE 16 -1 (-2150 2950)(-3125 2950);
FORCEPROP 2 LAST SIG_NAME H_CPU0_BMCINIT
J 0
(-2950 2960);
DISPLAY 0.617021 (-2950 2960);
PAINT ORANGE (-2950 2960);
WIRE 16 -1 (-2150 3000)(-3125 3000);
FORCEPROP 2 LAST SIG_NAME PU_CPU0_FRMAGENT
J 0
(-2950 3010);
DISPLAY 0.617021 (-2950 3010);
PAINT ORANGE (-2950 3010);
WIRE 16 -1 (-3125 3150)(-1850 3150);
FORCEPROP 2 LAST SIG_NAME H_CPU0_THERMTRIP_G_N
J 0
(-2950 3160);
DISPLAY 0.617021 (-2950 3160);
PAINT ORANGE (-2950 3160);
DOT 1 (-900 4550);
DOT 1 (-750 3750);
DOT 1 (-1000 4000);
DOT 1 (-750 3200);
DOT 1 (-700 2900);
DOT 1 (-950 2900);
DOT 1 (-700 2200);
DOT 1 (-950 2250);
DOT 1 (-1200 2900);
DOT 1 (-1450 2900);
DOT 1 (-1200 2300);
DOT 1 (-1450 2400);
DOT 1 (-1700 2450);
DOT 1 (-1075 1250);
DOT 1 (-5275 2350);
DOT 1 (-5350 2250);
DOT 1 (-5425 2150);
DOT 1 (-5500 2050);
DOT 1 (-5575 1950);
DOT 1 (-6875 2700);
DOT 1 (-7125 2700);
DOT 1 (-7350 2700);
DOT 1 (-7575 2700);
DOT 1 (-7800 2700);
DOT 1 (-7125 1800);
DOT 1 (-7350 1800);
DOT 1 (-7575 1800);
DOT 1 (-7800 1800);
DOT 1 (-750 3900);
DOT 1 (-1000 3850);
FORCENOTE
. 
(50 50) 0;
DISPLAY LEFT (50 50);
DISPLAY 1.021277 (50 50);
PAINT PURPLE (50 50);
FORCENOTE
DEFINITION
(-900 950) 0;
DISPLAY LEFT (-900 950);
DISPLAY 0.808511 (-900 950);
PAINT PURPLE (-900 950);
FORCENOTE
DEFINITION
(-2075 950) 0;
DISPLAY LEFT (-2075 950);
DISPLAY 0.808511 (-2075 950);
PAINT PURPLE (-2075 950);
FORCENOTE
PROC_ID [1:0]
(-2675 950) 0;
DISPLAY LEFT (-2675 950);
DISPLAY 0.808511 (-2675 950);
PAINT PURPLE (-2675 950);
FORCENOTE
RESERVED
(-1000 650) 0;
DISPLAY LEFT (-1000 650);
DISPLAY 0.638298 (-1000 650);
PAINT PURPLE (-1000 650);
FORCENOTE
RESERVED
(-1000 575) 0;
DISPLAY LEFT (-1000 575);
DISPLAY 0.638298 (-1000 575);
PAINT PURPLE (-1000 575);
FORCENOTE
MCP SUPPORT
(-1025 725) 0;
DISPLAY LEFT (-1025 725);
DISPLAY 0.638298 (-1025 725);
PAINT PURPLE (-1025 725);
FORCENOTE
3'B000
(-1450 850) 0;
DISPLAY LEFT (-1450 850);
DISPLAY 0.638298 (-1450 850);
PAINT PURPLE (-1450 850);
FORCENOTE
3'B001
(-1450 750) 0;
DISPLAY LEFT (-1450 750);
DISPLAY 0.638298 (-1450 750);
PAINT PURPLE (-1450 750);
FORCENOTE
3'B010
(-1450 650) 0;
DISPLAY LEFT (-1450 650);
DISPLAY 0.638298 (-1450 650);
PAINT PURPLE (-1450 650);
FORCENOTE
3'B111-3'B011
(-1450 575) 0;
DISPLAY LEFT (-1450 575);
DISPLAY 0.638298 (-1450 575);
PAINT PURPLE (-1450 575);
FORCENOTE
RESERVED
(-2250 650) 0;
DISPLAY LEFT (-2250 650);
DISPLAY 0.638298 (-2250 650);
PAINT PURPLE (-2250 650);
FORCENOTE
SKYLAKE PROCESSOR 
(-2250 850) 0;
DISPLAY LEFT (-2250 850);
DISPLAY 0.638298 (-2250 850);
PAINT PURPLE (-2250 850);
FORCENOTE
2'B11
(-2575 575) 0;
DISPLAY LEFT (-2575 575);
DISPLAY 0.638298 (-2575 575);
PAINT PURPLE (-2575 575);
FORCENOTE
2'B01
(-2575 750) 0;
DISPLAY LEFT (-2575 750);
DISPLAY 0.638298 (-2575 750);
PAINT PURPLE (-2575 750);
FORCENOTE
2'B00
(-2575 850) 0;
DISPLAY LEFT (-2575 850);
DISPLAY 0.638298 (-2575 850);
PAINT PURPLE (-2575 850);
FORCENOTE
2'B10
(-2575 650) 0;
DISPLAY LEFT (-2575 650);
DISPLAY 0.638298 (-2575 650);
PAINT PURPLE (-2575 650);
FORCENOTE
BOM_COST=PROC_SOCKET
(-7925 225) 0;
DISPLAY LEFT (-7925 225);
DISPLAY 0.808511 (-7925 225);
PAINT PURPLE (-7925 225);
FORCENOTE
ROOM=CPU0
(-7925 350) 0;
DISPLAY LEFT (-7925 350);
DISPLAY 0.808511 (-7925 350);
PAINT PURPLE (-7925 350);
FORCENOTE
RESERVED
(-2250 575) 0;
DISPLAY LEFT (-2250 575);
DISPLAY 0.638298 (-2250 575);
PAINT PURPLE (-2250 575);
FORCENOTE
RESERVED FOR FUTURE PROCESSOR
(-2250 750) 0;
DISPLAY LEFT (-2250 750);
DISPLAY 0.638298 (-2250 750);
PAINT PURPLE (-2250 750);
FORCENOTE
SKYLAKE - SKT0 - 1 OF 21
(-1650 150) 0;
DISPLAY LEFT (-1650 150);
DISPLAY 1.021277 (-1650 150);
PAINT RED (-1650 150);
FORCENOTE
HOST FABRIC INTERFACE
(-1025 775) 0;
DISPLAY LEFT (-1025 775);
DISPLAY 0.638298 (-1025 775);
PAINT PURPLE (-1025 775);
FORCENOTE
NON-MCP SUPPORT
(-1025 850) 0;
DISPLAY LEFT (-1025 850);
DISPLAY 0.638298 (-1025 850);
PAINT PURPLE (-1025 850);
FORCENOTE
PKG_ID[2:0]
(-1475 950) 0;
DISPLAY LEFT (-1475 950);
DISPLAY 0.808511 (-1475 950);
PAINT PURPLE (-1475 950);
FORCENOTE
PIROM_ADDR[2:0] 3B000
(-1275 1875) 0;
DISPLAY LEFT (-1275 1875);
DISPLAY 0.808511 (-1275 1875);
PAINT PURPLE (-1275 1875);
FORCENOTE
ALTERNATE: H63715-002
(-7875 4675) 0;
DISPLAY LEFT (-7875 4675);
DISPLAY 0.808511 (-7875 4675);
PAINT PURPLE (-7875 4675);
QUIT
